5
5
4
4
3
3
2
2
1
1
D D
C C
B B
A A
I2C_A_BUS
LSISAS2x28 EXPANDER
Block Diagram
I2C_A
I2C_B_BUS
I2C_C_BUS
Voltage 
Monitor
ADS1015
EEPROM
64Kb
24C64
Temp Sensor
TMP75  PCSx2
I2C_BI2C Buffer
PCA9511
I2C_CI2C Buffer
PCA9511
SAS Port
[0:14]
SAS Port
[20:23]
SAS Port
[24:27]
SAS Port
[16:19]
SMART SERIAL PORT
Serial debug port
Multi-ICE
MEMORY_BUS
CLOCK
RESET
LED DRIVER
   PCA9550
2R14P 
Debug Header
miniSAS
INT CONN_A
SAS2.0 x4
miniSAS
INT CONN_B
SAS2.0 x4
miniSAS
EXT CONN
SAS2.0 x4
SAS HDDx 15SAS2.0 x15
Reset IC
MAX6420
NOR Flash 
64Mbits
S29GL064
RESET
XMEM
PBSRAM
36Mbits
150MHz
Diff-OSC
CLOCK
3 PIN 
Header
20 PIN 
Header
SMART PORT
RE-DRIVER
PI2EQX6812
SEP_I2C
I2C Buffer
PCA9511
I2C_D_BUS
DEBUG PORT
ICE Signals
Reserve foot print
SAS Port
  [15]
ReserveSAS2.0 x1
EYE FINDERLED [64:65]Test Points
Sheet 01: BLOCK DIAGRAM
Sheet 02: POWER TREE
Sheet 03: SAS2x28 SAS PHY A
Sheet 04: SAS2x28 SAS PHY B
Sheet 05: SAS2x28 LED&GPIO
Sheet 06: SAS2x28 MEMORIES
Sheet 07: SAS2x28 POWER&GND
Sheet 08: SAS2x28 POWER&GND-2
Sheet 09: PBSRAM&FLASH
Sheet 10: INT&EXT SAS CONNs
Sheet 11: PCIe GOLD FINGER
Sheet 12: BUS SWITCHS
Sheet 13: I2C_A DEVICES
Sheet 14: I2C_B&C&D DEVICES
Sheet 15: DEBUG&RESET
Sheet 16: LEDs&HB
Sheet 17: 1D2V&1D8V_TPS74801
Sheet 18: VCORE 1V_TPS53353
Sheet 19: 3D3V_TPS54620&TPS2490
Sheet 20: CHANGE HISTORY(1/3)
Sheet 21: CHANGE HISTORY(2/3)
Sheet 21: CHANGE HISTORY(3/3)
Table of contents
Switch
TS5A23157
Temp Sensor
TMP400 
Title
Size Document Number Rev
Date: Sheet
of
Honey_Badger_SEB 1
BLOCK DIAGRAM
A3
1 22Tuesday, April 07, 2015
Wiwynn
H/W R&D Dept. II
8F,90,Sec. 1,Hsin Tai Wu Rd,
Hsichih, Taipei Hsien 221, Taiwan, R.O.C
Title
Size Document Number Rev
Date: Sheet
of
Honey_Badger_SEB 1
BLOCK DIAGRAM
A3
1 22Tuesday, April 07, 2015
Wiwynn
H/W R&D Dept. II
8F,90,Sec. 1,Hsin Tai Wu Rd,
Hsichih, Taipei Hsien 221, Taiwan, R.O.C
Title
Size Document Number Rev
Date: Sheet
of
Honey_Badger_SEB 1
BLOCK DIAGRAM
A3
1 22Tuesday, April 07, 2015
Wiwynn
H/W R&D Dept. II
8F,90,Sec. 1,Hsin Tai Wu Rd,
Hsichih, Taipei Hsien 221, Taiwan, R.O.C



5
5
4
4
3
3
2
2
1
1
D D
C C
B B
A A
POWER MAP
12V_PCIe
1V
PCIe CONN
   PU5
TPS2490DGSR
12V
5V
  PU6
UA78M05
     PU3
TPS53353DQPR-GP
EXPANDER U1
  DEBUG
CARD CONN
CN5
562R2F- GP
562 = 562 ohm, (2K2R means 2.2K ohm)
2 = size 0402
F = 1% tolerance
GP= Green Part (RoHS)
 R size code as below:
1 = 0201
2= 0402
3= 0603
5= 0805
6= 1206
 R tolerance code as below:
D=0.5%
F= 1%
J= 5%
SCD1U10V2KX-5GP
D1U = 0.1uF (2D2U means 2.2uF)
10Voltage (6D3V means 6.3V)
2 = size 0402, K tolerance
K=tolerance
[ C code as below:]
G=2%
J=5%
K=10%
M=20%
X=temp characteristics
[ C Series/Temp]
N=NPO
X=X7R/X5R
Y=Y5V
-5=different symbol/customer
GP= Green Part (RoHS)
FLASH
EEPROM
3D3V
U5
  LED
DRIVER
U6
VOLTAGE 
 SENSE
U7
U3
U2
   PU1
TPS74801RGW
1D2V
 TEMP
SENSOR
U8
U10
U12
RE-DRIVER U4
   PU2
TPS74801RGW
  I2C
BUFFER
U9
U11
U14
1D8V
RESET ICU13
   UART
TRANSCIVER
   PU4
TPS54320
EXPANDER U1
EXPANDERU1
PBSRAM
DY=Dummy parts
  =not populated
  PU3
TPS53353D
   PU2
TPS74801
1V 1D8V
   PU4
TPS54620RGY
PG EN PG
   PU7
SI4435DY
3D3V_L
3D3V
Reserved Power On Sequence
U20Analog
Switch
Title
Size Document Number Rev
Date: Sheet
of
Honey_Badger_SEB 1
POWER TREE
A3
2 22Tuesday, April 07, 2015
Wiwynn
H/W R&D Dept. II
8F,90,Sec. 1,Hsin Tai Wu Rd,
Hsichih, Taipei Hsien 221, Taiwan, R.O.C
Title
Size Document Number Rev
Date: Sheet
of
Honey_Badger_SEB 1
POWER TREE
A3
2 22Tuesday, April 07, 2015
Wiwynn
H/W R&D Dept. II
8F,90,Sec. 1,Hsin Tai Wu Rd,
Hsichih, Taipei Hsien 221, Taiwan, R.O.C
Title
Size Document Number Rev
Date: Sheet
of
Honey_Badger_SEB 1
POWER TREE
A3
2 22Tuesday, April 07, 2015
Wiwynn
H/W R&D Dept. II
8F,90,Sec. 1,Hsin Tai Wu Rd,
Hsichih, Taipei Hsien 221, Taiwan, R.O.C



5
5
4
4
3
3
2
2
1
1
D D
C C
B B
A A
150MHz 50ppm
Re-Driver IC 
lane 0 and 1 Re-Driver IC 
lane 0 and 1
EXPANDER SAS PORTs
OSC_REFCLK_P
OSC_REFCLK_N
OSC_OE
SAS_REFCLK_P
SAS_REFCLK_N
SAS_RTRIM
SAS_RTRIM_N
SAS_HDD_RX0_P
SAS_HDD_RX0_N
SAS_HDD_RX1_P
SAS_HDD_RX1_N
SAS_HDD_RX2_P
SAS_HDD_RX2_N
SAS_HDD_RX3_P
SAS_HDD_RX3_N
SAS_HDD_RX4_P
SAS_HDD_RX4_N
SAS_HDD_RX5_P
SAS_HDD_RX5_N
SAS_HDD_RX6_P
SAS_HDD_RX6_N
SAS_HDD_REDV_RX7_P
SAS_HDD_REDV_RX7_N
SAS_HDD_REDV_RX8_P
SAS_HDD_REDV_RX8_N
SAS_HDD_RX9_P
SAS_HDD_RX9_N
SAS_HDD_RX10_P
SAS_HDD_RX10_N
SAS_HDD_RX11_P
SAS_HDD_RX11_N
SAS_HDD_RX12_P
SAS_HDD_RX12_N
SAS_HDD_RX13_P
SAS_HDD_RX13_N
SAS_HDD_RX14_P
SAS_HDD_RX14_N
SAS_HDD_RX15_P
SAS_HDD_RX15_N
SAS_HDD_TX0_P
SAS_HDD_TX11_P
SAS_HDD_TX12_P
SAS_HDD_TX1_N
SAS_HDD_TX2_P
SAS_HDD_TX3_P
SAS_HDD_TX6_P
SAS_HDD_TX6_N
SAS_HDD_TX7_P
SAS_HDD_TX7_N
SAS_HDD_TX8_P
SAS_HDD_TX1_P
SAS_HDD_TX4_P
SAS_HDD_TX5_P
SAS_HDD_TX0_N
SAS_HDD_TX4_N
SAS_HDD_TX5_N
SAS_HDD_TX2_N
SAS_HDD_TX15_P
SAS_HDD_TX13_N
SAS_HDD_TX14_N
SAS_HDD_TX9_P
SAS_HDD_TX10_N
SAS_HDD_TX10_P
SAS_HDD_TX9_N
SAS_HDD_TX11_N
SAS_HDD_TX8_N
SAS_HDD_TX12_N
SAS_HDD_TX15_N
SAS_HDD_TX13_P
SAS_HDD_TX3_N
SAS_HDD_TX14_P
EXPANDER_TEM
OSC_DIFF
1V
1V
3D3V
SAS_HDD_RX0_P11
SAS_HDD_RX0_N11
SAS_HDD_RX1_P11
SAS_HDD_RX1_N11
SAS_HDD_RX2_P11
SAS_HDD_RX2_N11
SAS_HDD_RX3_P11
SAS_HDD_RX3_N11
SAS_HDD_RX4_P11
SAS_HDD_RX4_N11
SAS_HDD_RX5_P11
SAS_HDD_RX5_N11
SAS_HDD_RX6_P11
SAS_HDD_RX6_N11
SAS_HDD_REDV_RX7_P13
SAS_HDD_REDV_RX7_N13
SAS_HDD_REDV_RX8_P13
SAS_HDD_REDV_RX8_N13
SAS_HDD_RX9_P11
SAS_HDD_RX9_N11
SAS_HDD_RX10_P11
SAS_HDD_RX10_N11
SAS_HDD_RX11_P11
SAS_HDD_RX11_N11
SAS_HDD_RX12_P11
SAS_HDD_RX12_N11
SAS_HDD_RX13_P11
SAS_HDD_RX13_N11
SAS_HDD_RX14_P11
SAS_HDD_RX14_N11
SAS_HDD_RX15_P11
SAS_HDD_RX15_N11
SAS_HDD_CONN_TX0_P 11
SAS_HDD_CONN_TX0_N 11
SAS_HDD_CONN_TX1_P 11
SAS_HDD_CONN_TX4_P 11
SAS_HDD_CONN_TX2_P 11
SAS_HDD_CONN_TX3_P 11
SAS_HDD_CONN_TX1_N 11
SAS_HDD_CONN_TX2_N 11
SAS_HDD_CONN_TX3_N 11
SAS_HDD_CONN_TX4_N 11
SAS_HDD_CONN_TX5_P 11
SAS_HDD_CONN_TX6_P 11
SAS_HDD_REDV_TX7_P 13
SAS_HDD_REDV_TX8_P 13
SAS_HDD_CONN_TX9_P 11
SAS_HDD_CONN_TX10_P 11
SAS_HDD_CONN_TX11_P 11
SAS_HDD_CONN_TX12_P 11
SAS_HDD_CONN_TX13_P 11
SAS_HDD_CONN_TX14_P 11
SAS_HDD_CONN_TX15_P 11
SAS_HDD_CONN_TX5_N 11
SAS_HDD_CONN_TX6_N 11
SAS_HDD_REDV_TX7_N 13
SAS_HDD_REDV_TX8_N 13
SAS_HDD_CONN_TX9_N 11
SAS_HDD_CONN_TX10_N 11
SAS_HDD_CONN_TX11_N 11
SAS_HDD_CONN_TX12_N 11
SAS_HDD_CONN_TX13_N 11
SAS_HDD_CONN_TX14_N 11
SAS_HDD_CONN_TX15_N 11
Title
Size Document Number Rev
Date: Sheet
of
Honey_Badger_SEB 1
SAS2x28 SAS PHY A
A3
3 22Tuesday, April 07, 2015
Wiwynn
H/W R&D Dept. II
8F,90,Sec. 1,Hsin Tai Wu Rd,
Hsichih, Taipei Hsien 221, Taiwan, R.O.C
Title
Size Document Number Rev
Date: Sheet
of
Honey_Badger_SEB 1
SAS2x28 SAS PHY A
A3
3 22Tuesday, April 07, 2015
Wiwynn
H/W R&D Dept. II
8F,90,Sec. 1,Hsin Tai Wu Rd,
Hsichih, Taipei Hsien 221, Taiwan, R.O.C
Title
Size Document Number Rev
Date: Sheet
of
Honey_Badger_SEB 1
SAS2x28 SAS PHY A
A3
3 22Tuesday, April 07, 2015
Wiwynn
H/W R&D Dept. II
8F,90,Sec. 1,Hsin Tai Wu Rd,
Hsichih, Taipei Hsien 221, Taiwan, R.O.C
R6
49D9R2F-GP
R6
49D9R2F-GP
1 2
L20 BLM15HD182SN1-GPL20 BLM15HD182SN1-GP1 2
C16 SCD01U50V2KX-1GPC16 SCD01U50V2KX-1GP1 2
L19 BLM15HD182SN1-GPL19 BLM15HD182SN1-GP1 2
L6 BLM15HD182SN1-GPL6 BLM15HD182SN1-GP1 2
C2 
SC1U10V2KX-4-GP 
C2 
SC1U10V2KX-4-GP 
1 2
R9
1K5R2F-2-GP
R9
1K5R2F-2-GP
1 2
L3 BLM15HD182SN1-GPL3 BLM15HD182SN1-GP1 2
L11 BLM15HD182SN1-GPL11 BLM15HD182SN1-GP1 2
L18 BLM15HD182SN1-GPL18 BLM15HD182SN1-GP1 2
C9 SCD01U50V2KX-1GPC9 SCD01U50V2KX-1GP1 2
C30 SCD01U50V2KX-1GPC30 SCD01U50V2KX-1GP1 2
C23 SCD01U50V2KX-1GPC23 SCD01U50V2KX-1GP1 2
L2 BLM15HD182SN1-GPL2 BLM15HD182SN1-GP1 2
C17 SCD01U50V2KX-1GPC17 SCD01U50V2KX-1GP1 2
L12 BLM15HD182SN1-GPL12 BLM15HD182SN1-GP1 2
L15 BLM15HD182SN1-GPL15 BLM15HD182SN1-GP1 2
C5 SCD01U50V2KX-1GPC5 SCD01U50V2KX-1GP1 2
C26 SCD01U50V2KX-1GPC26 SCD01U50V2KX-1GP1 2
L10 BLM15HD182SN1-GPL10 BLM15HD182SN1-GP1 2
C34 SCD01U50V2KX-1GPC34 SCD01U50V2KX-1GP1 2
OSC1
OSC-150MHZ-GP
OSC1
OSC-150MHZ-GP
OE1
GND3 OUT 4
VDD 6
OUT# 5NC#22
C20 SCD01U50V2KX-1GPC20 SCD01U50V2KX-1GP1 2
L14 BLM15HD182SN1-GPL14 BLM15HD182SN1-GP1 2
R3
0R2J-2-GP
R3
0R2J-2-GP
1 2
L16 BLM15HD182SN1-GPL16 BLM15HD182SN1-GP1 2
C14 SCD01U50V2KX-1GPC14 SCD01U50V2KX-1GP1 2
L21 BLM15HD182SN1-GPL21 BLM15HD182SN1-GP1 2
C10 SCD01U50V2KX-1GPC10 SCD01U50V2KX-1GP1 2
C31 SCD01U50V2KX-1GPC31 SCD01U50V2KX-1GP1 2
L4 BLM15HD182SN1-GPL4 BLM15HD182SN1-GP1 2
R2
4K75R2F-1-GP
R2
4K75R2F-1-GP
1 2
C6 SCD01U50V2KX-1GPC6 SCD01U50V2KX-1GP1 2
R7 
49D9R2F-GP 
R7 
49D9R2F-GP 
1 2
C27 SCD01U50V2KX-1GPC27 SCD01U50V2KX-1GP1 2
C11 SCD01U50V2KX-1GPC11 SCD01U50V2KX-1GP1 2
L28 BLM15HD182SN1-GPL28 BLM15HD182SN1-GP1 2
L8 BLM15HD182SN1-GPL8 BLM15HD182SN1-GP1 2
C35 SCD01U50V2KX-1GPC35 SCD01U50V2KX-1GP1 2
L32 BLM15HD182SN1-GPL32 BLM15HD182SN1-GP1 2
L1
MPZ1608S331A-GP
L1
MPZ1608S331A-GP
1 2
C21 SCD01U50V2KX-1GPC21 SCD01U50V2KX-1GP1 2
C4 SCD01U50V2KX-1GPC4 SCD01U50V2KX-1GP1 2
C15 SCD01U50V2KX-1GPC15 SCD01U50V2KX-1GP1 2
C3
SCD01U50V2KX-1GP
DYC3
SCD01U50V2KX-1GP
DY
1 2
L13 BLM15HD182SN1-GPL13 BLM15HD182SN1-GP1 2
L31 BLM15HD182SN1-GPL31 BLM15HD182SN1-GP1 2
C24 SCD01U50V2KX-1GPC24 SCD01U50V2KX-1GP1 2
L5 BLM15HD182SN1-GPL5 BLM15HD182SN1-GP1 2
C18 SCD01U50V2KX-1GPC18 SCD01U50V2KX-1GP1 2
L7 BLM15HD182SN1-GPL7 BLM15HD182SN1-GP1 2
R5 
220R2F-GP 
DY R5 
220R2F-GP 
DY 
1 2
C32 SCD01U50V2KX-1GPC32 SCD01U50V2KX-1GP1 2
L9 BLM15HD182SN1-GPL9 BLM15HD182SN1-GP1 2
L27 BLM15HD182SN1-GPL27 BLM15HD182SN1-GP1 2
C7 SCD01U50V2KX-1GPC7 SCD01U50V2KX-1GP1 2
C28 SCD01U50V2KX-1GPC28 SCD01U50V2KX-1GP1 2
C12 SCD01U50V2KX-1GPC12 SCD01U50V2KX-1GP1 2
L30 BLM15HD182SN1-GPL30 BLM15HD182SN1-GP1 2
L24 BLM15HD182SN1-GPL24 BLM15HD182SN1-GP1 2
C25 SCD01U50V2KX-1GPC25 SCD01U50V2KX-1GP1 2
L33 BLM15HD182SN1-GPL33 BLM15HD182SN1-GP1 2
L29 BLM15HD182SN1-GPL29 BLM15HD182SN1-GP1 2
L23 BLM15HD182SN1-GPL23 BLM15HD182SN1-GP1 2
L22 BLM15HD182SN1-GPL22 BLM15HD182SN1-GP1 2
R4
0R2J-2-GP
R4
0R2J-2-GP
1 2
R1
5D11R3F-1-GP
R1
5D11R3F-1-GP
1 2
C33 SCD01U50V2KX-1GPC33 SCD01U50V2KX-1GP1 2
R8 
49D9R2F-GP 
R8 
49D9R2F-GP 
1 2
L26 BLM15HD182SN1-GPL26 BLM15HD182SN1-GP1 2
C19 SCD01U50V2KX-1GPC19 SCD01U50V2KX-1GP1 2
L17 BLM15HD182SN1-GPL17 BLM15HD182SN1-GP1 2
3 OF 7
SAS PHY[15:0] 
U1C
LSISAS2X28-62148B1-1-GP
3 OF 7
SAS PHY[15:0] 
U1C
LSISAS2X28-62148B1-1-GP
REF_CLK+B28
REF_CLK-C28
RTRIMM22
RTRIM#M23
RX0+AD11
RX0-AE11
RX1+AD12
RX1-AE12
RX2+AD13
RX2-AE13
RX3+AD14
RX3-AE14
RX4+AD15
RX4-AE15
RX5+AD16
RX5-AE16
RX6+AD17
RX6-AE17
RX7+AD18
RX7-AE18
TX0+ AG11
TX1+ AG12
TX2+ AG13
TX3+ AG14
TX4+ AG15
TX5+ AG16
TX6+ AG17
TX7+ AG18
TX0- AH11
TX1- AH12
TX2- AH13
TX3- AH14
TX4- AH15
TX5- AH16
TX6- AH17
TX7- AH18
TX8+ AG19
TX8- AH19
TX9+ AG20
TX9- AH20
TX10+ AG21
TX10- AH21
TX11+ AG22
TX11- AH22
TX12+ B24
TX12- A24
TX13+ B23
TX13- A23
TX14+ B22
TX14- A22
TX15+ B21
TX15- A21
RX8+AD19
RX8-AE19
RX9+AD20
RX9-AE20
RX10+AD21
RX10-AE21
RX11+AD22
RX11-AE22
RX12+E24
RX12-D24
RX13+E23
RX13-D23
RX14+E22
RX14-D22
RX15+E21
RX15-D21
C1 
SCD01U50V2KX-1GP 
C1 
SCD01U50V2KX-1GP 
1 2
L25 BLM15HD182SN1-GPL25 BLM15HD182SN1-GP1 2
C22 SCD01U50V2KX-1GPC22 SCD01U50V2KX-1GP1 2
C8 SCD01U50V2KX-1GPC8 SCD01U50V2KX-1GP1 2
C29 SCD01U50V2KX-1GPC29 SCD01U50V2KX-1GP1 2
C13 SCD01U50V2KX-1GPC13 SCD01U50V2KX-1GP1 2



5
5
4
4
3
3
2
2
1
1
D D
C C
B B
A A
EXPANDER SAS PORTs
HEAT-SINK LOCK
SAS_EXT_RX16_P
SAS_EXT_RX16_N
SAS_EXT_RX17_P
SAS_EXT_RX17_N
SAS_EXT_RX18_P
SAS_EXT_RX18_N
SAS_INTB_TX27_N
SAS_INTB_TX27_P
SAS_INTB_TX26_N
SAS_INTB_TX26_P
SAS_INTB_TX25_N
SAS_INTB_TX25_P
SAS_INTA_TX22_N
SAS_INTA_TX22_P
SAS_INTA_TX21_N
SAS_INTA_TX21_P
SAS_INTA_TX20_N
SAS_INTA_TX20_P
SAS_INTB_TX24_N
SAS_INTA_TX23_P
SAS_EXT_TX16_P
SAS_EXT_TX16_N
SAS_EXT_TX17_P
SAS_EXT_TX17_N
SAS_EXT_TX18_P
SAS_EXT_TX18_N
SAS_EXT_TX19_N
SAS_EXT_TX19_P
SAS_EXT_RX19_N
SAS_EXT_RX19_P
SAS_INTA_RX20_P
SAS_INTA_RX20_N
SAS_INTA_RX21_P
SAS_INTA_RX21_N
SAS_INTA_RX22_P
SAS_INTA_RX22_N
SAS_INTA_RX23_P
SAS_INTA_RX23_N
SAS_INTB_RX24_P
SAS_INTB_RX25_P
SAS_INTB_RX26_N
SAS_INTB_RX24_N
SAS_INTB_RX25_N
SAS_INTB_RX26_P
SAS_INTB_RX27_N
SAS_INTB_RX27_P
SAS_INTA_TX23_N
SAS_INTB_TX24_P
1V
1V
SAS_EXT_RX16_P10
SAS_EXT_RX16_N10
SAS_EXT_RX17_P10
SAS_EXT_RX17_N10
SAS_EXT_RX18_P10
SAS_EXT_RX18_N10
SAS_EXT_CONN_TX16_P 10
SAS_EXT_CONN_TX16_N 10
SAS_EXT_CONN_TX17_P 10
SAS_EXT_CONN_TX17_N 10
SAS_EXT_CONN_TX18_N 10
SAS_EXT_CONN_TX18_P 10
SAS_EXT_CONN_TX19_N 10
SAS_EXT_CONN_TX19_P 10SAS_EXT_RX19_P10
SAS_EXT_RX19_N10
SAS_INTA_RX20_P10
SAS_INTA_RX20_N10
SAS_INTA_RX21_P10
SAS_INTA_RX21_N10
SAS_INTA_RX22_P10
SAS_INTA_RX22_N10
SAS_INTA_RX23_P10
SAS_INTA_RX23_N10
SAS_INTB_RX24_P10
SAS_INTB_RX24_N10
SAS_INTB_RX25_P10
SAS_INTB_RX25_N10
SAS_INTB_RX26_P10
SAS_INTB_RX26_N10
SAS_INTB_RX27_P10
SAS_INTB_RX27_N10
SAS_INTA_CONN_TX20_P 10
SAS_INTA_CONN_TX20_N 10
SAS_INTA_CONN_TX21_P 10
SAS_INTA_CONN_TX21_N 10
SAS_INTA_CONN_TX22_P 10
SAS_INTA_CONN_TX22_N 10
SAS_INTA_CONN_TX23_P 10
SAS_INTA_CONN_TX23_N 10
SAS_INTB_CONN_TX24_P 10
SAS_INTB_CONN_TX25_P 10
SAS_INTB_CONN_TX26_P 10
SAS_INTB_CONN_TX24_N 10
SAS_INTB_CONN_TX25_N 10
SAS_INTB_CONN_TX26_N 10
SAS_INTB_CONN_TX27_P 10
SAS_INTB_CONN_TX27_N 10
Title
Size Document Number Rev
Date: Sheet
of
Honey_Badger_SEB 1
SAS2x28 SAS PHY B
A3
4 22Tuesday, April 07, 2015
Wiwynn
H/W R&D Dept. II
8F,90,Sec. 1,Hsin Tai Wu Rd,
Hsichih, Taipei Hsien 221, Taiwan, R.O.C
Title
Size Document Number Rev
Date: Sheet
of
Honey_Badger_SEB 1
SAS2x28 SAS PHY B
A3
4 22Tuesday, April 07, 2015
Wiwynn
H/W R&D Dept. II
8F,90,Sec. 1,Hsin Tai Wu Rd,
Hsichih, Taipei Hsien 221, Taiwan, R.O.C
Title
Size Document Number Rev
Date: Sheet
of
Honey_Badger_SEB 1
SAS2x28 SAS PHY B
A3
4 22Tuesday, April 07, 2015
Wiwynn
H/W R&D Dept. II
8F,90,Sec. 1,Hsin Tai Wu Rd,
Hsichih, Taipei Hsien 221, Taiwan, R.O.C
L49 BLM15HD182SN1-GPL49 BLM15HD182SN1-GP1 2
L54 BLM15HD182SN1-GPL54 BLM15HD182SN1-GP1 2
CN9
FOX-CON2-14-GP
CN9
FOX-CON2-14-GP
1
2
C45 SCD01U50V2KX-1GPC45 SCD01U50V2KX-1GP1 2
L55 BLM15HD182SN1-GPL55 BLM15HD182SN1-GP1 2
L37 BLM15HD182SN1-GPL37 BLM15HD182SN1-GP1 2
C252 SCD01U50V2KX-1GPC252 SCD01U50V2KX-1GP1 2
C44 SCD01U50V2KX-1GPC44 SCD01U50V2KX-1GP1 2
L45 BLM15HD182SN1-GPL45 BLM15HD182SN1-GP1 2
C52 SCD01U50V2KX-1GPC52 SCD01U50V2KX-1GP1 2
L36 BLM15HD182SN1-GPL36 BLM15HD182SN1-GP1 2
C39 SCD01U50V2KX-1GPC39 SCD01U50V2KX-1GP1 2
C36 SCD01U50V2KX-1GPC36 SCD01U50V2KX-1GP1 2
L53 BLM15HD182SN1-GPL53 BLM15HD182SN1-GP1 2
L35 BLM15HD182SN1-GPL35 BLM15HD182SN1-GP1 2
C43 SCD01U50V2KX-1GPC43 SCD01U50V2KX-1GP1 2
L46 BLM15HD182SN1-GPL46 BLM15HD182SN1-GP1 2
CN8
FOX-CON2-14-GP
CN8
FOX-CON2-14-GP
1
2
L52 BLM15HD182SN1-GPL52 BLM15HD182SN1-GP1 2
C51 SCD01U50V2KX-1GPC51 SCD01U50V2KX-1GP1 2
L51 BLM15HD182SN1-GPL51 BLM15HD182SN1-GP1 2
C49 SCD01U50V2KX-1GPC49 SCD01U50V2KX-1GP1 2
L43 BLM15HD182SN1-GPL43 BLM15HD182SN1-GP1 2
L67 BLM15HD182SN1-GPL67 BLM15HD182SN1-GP1 2
L44 BLM15HD182SN1-GPL44 BLM15HD182SN1-GP1 2
C247 SCD01U50V2KX-1GPC247 SCD01U50V2KX-1GP1 2
C57 SCD01U50V2KX-1GPC57 SCD01U50V2KX-1GP1 2
L42 BLM15HD182SN1-GPL42 BLM15HD182SN1-GP1 2
L38 BLM15HD182SN1-GPL38 BLM15HD182SN1-GP1 2
C56 SCD01U50V2KX-1GPC56 SCD01U50V2KX-1GP1 2
C55 SCD01U50V2KX-1GPC55 SCD01U50V2KX-1GP1 2
L39 BLM15HD182SN1-GPL39 BLM15HD182SN1-GP1 2
L50 BLM15HD182SN1-GPL50 BLM15HD182SN1-GP1 2
C54 SCD01U50V2KX-1GPC54 SCD01U50V2KX-1GP1 2
L40 BLM15HD182SN1-GPL40 BLM15HD182SN1-GP1 2
4 OF 7
SAS PHY[19:16] 
U1D
LSISAS2X28-62148B1-1-GP
4 OF 7
SAS PHY[19:16] 
U1D
LSISAS2X28-62148B1-1-GP
RX16+E20
RX17+E19
RX18+E18
RX19+E17
RX20+E16
RX21+E15
RX22+E14
RX23+E13
RX16-D20
RX17-D19
RX18-D18
RX19-D17
RX20-D16
RX21-D15
RX22-D14
RX23-D13
TX16+ B20
TX17+ B19
TX18+ B18
TX19+ B17
TX20+ B16
TX21+ B15
TX22+ B14
TX23+ B13
TX16- A20
TX17- A19
TX18- A18
TX19- A17
TX20- A16
TX21- A15
TX22- A14
TX23- A13
TX24+ B12
TX24- A12
TX25+ B11
TX25- A11
TX26+ B10
TX26- A10
TX27+ B9
TX27- A9
NC#AG7 AG7
NC#AH7 AH7
NC#AG8 AG8
NC#AH8 AH8
NC#AG9 AG9
NC#AH9 AH9
NC#AG10 AG10
NC#AH10 AH10
NC#B8 B8
NC#A8 A8
NC#B7 B7
NC#A7 A7
NC#B6 B6
NC#A6 A6
NC#B5 B5
NC#A5 A5
RX24+E12
RX24-D12
RX25+E11
RX25-D11
RX26+E10
RX26-D10
RX27+E9
RX27-D9
NC#AD7AD7
NC#AE7AE7
NC#AD8AD8
NC#AE8AE8
NC#AD9AD9
NC#AE9AE9
NC#AD10AD10
NC#AE10AE10
NC#E8E8
NC#D8D8
NC#E7E7
NC#D7D7
NC#E6E6
NC#D6D6
NC#E5E5
NC#D5D5
L48 BLM15HD182SN1-GPL48 BLM15HD182SN1-GP1 2
C41 SCD01U50V2KX-1GPC41 SCD01U50V2KX-1GP1 2
C38 SCD01U50V2KX-1GPC38 SCD01U50V2KX-1GP1 2
C53 SCD01U50V2KX-1GPC53 SCD01U50V2KX-1GP1 2
C42 SCD01U50V2KX-1GPC42 SCD01U50V2KX-1GP1 2
L47 BLM15HD182SN1-GPL47 BLM15HD182SN1-GP1 2
L34 BLM15HD182SN1-GPL34 BLM15HD182SN1-GP1 2
C50 SCD01U50V2KX-1GPC50 SCD01U50V2KX-1GP1 2
C40 SCD01U50V2KX-1GPC40 SCD01U50V2KX-1GP1 2
L66 BLM15HD182SN1-GPL66 BLM15HD182SN1-GP1 2
C48 SCD01U50V2KX-1GPC48 SCD01U50V2KX-1GP1 2
C37 SCD01U50V2KX-1GPC37 SCD01U50V2KX-1GP1 2
C47 SCD01U50V2KX-1GPC47 SCD01U50V2KX-1GP1 2
L41 BLM15HD182SN1-GPL41 BLM15HD182SN1-GP1 2
C46 SCD01U50V2KX-1GPC46 SCD01U50V2KX-1GP1 2



5
5
4
4
3
3
2
2
1
1
D D
C C
B B
A A
SAS_HDD_PWR6
SAS_Activity_LED18
SAS_Fault_LED17
SAS_FSEL0
SAS_Status_LED98
SAS_ADC1
SAS_Status_LED97
SAS_Activity_LED17
SAS_GPIO8
SAS_Fault_LED18
SAS_HDD_PWR7
SAS_Activity_LED16
SAS_Fault_LED20
SAS_Status_LED96
SAS_BLINKIN
SAS_SIO_CLKIN
SAS_Fault_LED19
SAS_GPIO9
SAS_Status_LED95
SAS_FSEL1
SAS_HDD_PWR8
SAS_TDO
SAS_HDD_PRE14
SAS_SCAN_ENABLE
SAS_Fault_LED21
SAS_ICE_TDO
SAS_SIO_DIN
SAS_SXPACTIVE
SAS_Fault_LED4
SAS_HDD_PRE13
SAS_Status_LED94
SAS_Fault_LED22
SAS_Activity_LED20
SAS_Fault_LED5
SAS_HDD_PWR9
SAS_GPIO10
SAS_ICE_RTCK
SAS_BLINKIN_LED
SAS_Status_LED93
SAS_CPUMODE1
SAS_HDD_PRE12
SAS_Fault_LED23
SAS_Status_LED92
SAS_TCK
SAS_HDD_PRE11
SAS_Activity_LED21
RESET IC_RESET#
SAS_SIO_CLKOUT
SAS_SIO_LOADIN
SAS_Fault_LED24
SAS_Fault_LED6
SAS_HDD_PRE10
SAS_HDD_PWR10
SAS_EXPACTIVE
SAS_Activity_LED22
SAS_ICE_TCK
SAS_Fault_LED25
SAS_HDD_PRE9
SAS_Activity_LED23
SAS_ARM_RESET
SAS_Fault_LED7
SAS_HDD_PRE8
SAS_Fault_LED26
SAS_OSC_RC 
SAS_Activity_LED24
SAS_TRST#
SAS_HDD_PWR11
SAS_SIO_DOUT
SAS_TDI
SAS_HDD_PRE7
SAS_Activity_LED25
SAS_Fault_LED27
SAS_HDD_PRE6
SAS_Fault_LED8
SAS_ICE_TDI
SAS_EXPACTIVE_LED
SAS_GPIO0
SAS_SIO_LOADOUT
SAS_Activity_LED26
SAS_HDD_PRE5
MDIO_DATA
SAS_HDD_PWR12
SAS_Activity_LED27
SAS_GPIO1
SAS_Status_LED91
SAS_Fault_LED9
SAS_Status_LED90
MDIO_CLK
SAS_HDD_PRE4
SAS_Activity_LED28
SAS_ICE_TMS
SAS_REF_PLL_CONTER_VDD
SAS_Fault_LED30
SAS_HDD_PWR13
SAS_HDD_PRE3
SAS_HDD_PWR0
SAS_ADCTP
SAS_Fault_LED0
SAS_Activity_LED29
SAS_INTERLEAVE_EN
SAS_TDIODE_VSS
SAS_Fault_LED10
SAS_ADC0
SAS_GPIO2
SAS_Fault_LED31
SAS_Activity_LED30
SAS_BLINKOUT
SAS_HDD_PWR14
SAS_SUPPORT_CELL
SAS_Fault_LED32
SAS_ICE_TRST#
SAS_Activity_LED31
SAS_TN#
SAS_HDD_PRE1
SAS_Fault_LED11
SAS_Activity_LED32
SAS_GPIO3
SAS_HDD_PWR1
SAS_Fault_LED33
SAS_HDD_PRE0
SAS_TDIODE_P
SAS_Activity_LED33
SAS_HDD_PWR15
SAS_Fault_LED12
SAS_Fault_LED34
SAS_SXPACTIVE_LED
SAS_Status_LED107
SAS_IDDT
SAS_Activity_LED34
SAS_HDD_PWR2
SAS_GPIO4
SAS_Fault_LED35
SAS_Status_LED106
SAS_Activity_LED35
SAS_Fault_LED13
SAS_Status_LED88
SAS_Status_LED105
SAS_Fault_LED1
SAS_HDD_PWR3
SAS_Status_LED104
SAS_BLINKOUT_LED
SAS_Fault_LED2
SAS_GPIO5
SAS_Fault_LED14
SAS_Fault_LED3
SAS_Status_LED103
SAS_HDD_PWR4
SAS_Status_LED102
SAS_Fault_LED15
SAS_GPIO6
SAS_Status_LED101
SAS_Status_LED89
SAS_HDD_PWR5
SAS_PROCMON
SAS_Status_LED100
SAS_Fault_LED16
SAS_TMS
SAS_Activity_LED19
SAS_CPUMODE0
SAS_OSC
SAS_GPIO7
SAS_Status_LED99
SAS_REF_PLL_VDD
SAS_REF_PLL_DOWN_VDD
SAS_HDD_PRE2
SAS_HDD_PRE15
SAS_ARM_RESET
SAS_FSEL0
SAS_FSEL1
SAS_INTERLEAVE_EN
SAS_CPUMODE0
SAS_CPUMODE1
3D3V
3D3V
1V
3D3V
3D3V
3D3V
3D3V
1V
1V
3D3V
SAS_Fault_LED411
RESET IC_RESET#9,15
RESET IC_RESET#9,15
SAS_Fault_LED511
SAS_Fault_LED611
SAS_Fault_LED711
SAS_Fault_LED811
SAS_Fault_LED911
SAS_Fault_LED1011
SAS_Fault_LED1111
SAS_Fault_LED1211
SAS_Fault_LED1311
SAS_Fault_LED1411
SAS_ICE_TCK15
SAS_ICE_TRST#15
SAS_ICE_TMS15
SAS_ICE_TDI15 SAS_ICE_TDO 15
SAS_ICE_RTCK 15
SAS_GPIO011
SAS_GPIO111
SAS_GPIO312
SAS_GPIO216
SAS_GPIO411
SAS_GPIO511
SAS_GPIO611
SAS_Fault_LED011
SAS_Fault_LED111
SAS_Fault_LED211
SAS_Fault_LED311
SAS_HDD_PRE0 11
SAS_HDD_PRE1 11
SAS_HDD_PRE2 11
SAS_HDD_PRE3 11
SAS_HDD_PRE4 11
SAS_HDD_PRE5 11
SAS_HDD_PRE6 11
SAS_HDD_PRE7 11
SAS_HDD_PRE8 11
SAS_HDD_PRE9 11
SAS_HDD_PRE10 11
SAS_HDD_PRE11 11
SAS_HDD_PRE12 11
SAS_HDD_PRE13 11
SAS_HDD_PRE14 11
SAS_HDD_PWR012
SAS_HDD_PWR112
SAS_HDD_PWR212
SAS_HDD_PWR312
SAS_HDD_PWR412
SAS_HDD_PWR512
SAS_HDD_PWR612
SAS_HDD_PWR712
SAS_HDD_PWR812
SAS_HDD_PWR912
SAS_HDD_PWR1012
SAS_HDD_PWR1112
SAS_HDD_PWR1212
SAS_HDD_PWR1312
SAS_HDD_PWR1412
MDIO_CLK15
MDIO_DATA15
SAS_Activity_LED18 15
SAS_Activity_LED17 15
SAS_Activity_LED16 16
SAS_Status_LED8915
SAS_Status_LED8816
SAS_Status_LED90 15
SAS_Activity_LED19 15
SAS_Status_LED91 15
SAS_Activity_LED20 16
SAS_Status_LED92 16
SAS_Activity_LED24 16
SAS_Status_LED96 16
SAS_GPIO716
SAS_HDD_PRE15 11
SAS_GPIO815
SAS_GPIO915
SAS_Fault_LED1511
SAS_HDD_PWR1512
SAS_GPIO1011
FCB_HW_REVISION11
DPB_HW_REVISION11
PEER_1A_2A_HB11
PEER_1B_2B_HB11
SAS_TDIODE_P14 SAS_TDIODE_VSS 14
Title
Size Document Number Rev
Date: Sheet
of
Honey_Badger_SEB 1
SAS2x28 LED&GPIO
Custom
5 22Tuesday, April 07, 2015
Wiwynn
H/W R&D Dept. II
8F,90,Sec. 1,Hsin Tai Wu Rd,
Hsichih, Taipei Hsien 221, Taiwan, R.O.C
Title
Size Document Number Rev
Date: Sheet
of
Honey_Badger_SEB 1
SAS2x28 LED&GPIO
Custom
5 22Tuesday, April 07, 2015
Wiwynn
H/W R&D Dept. II
8F,90,Sec. 1,Hsin Tai Wu Rd,
Hsichih, Taipei Hsien 221, Taiwan, R.O.C
Title
Size Document Number Rev
Date: Sheet
of
Honey_Badger_SEB 1
SAS2x28 LED&GPIO
Custom
5 22Tuesday, April 07, 2015
Wiwynn
H/W R&D Dept. II
8F,90,Sec. 1,Hsin Tai Wu Rd,
Hsichih, Taipei Hsien 221, Taiwan, R.O.C
R25
470R2F-GP
DYR25
470R2F-GP
DY
1 2
TP59 TPAD32-GPTP59 TPAD32-GP1
TP68 TPAD32-GPTP68 TPAD32-GP1
TP57 TPAD32-GPTP57 TPAD32-GP1
TP64 TPAD32-GPTP64 TPAD32-GP1
R41
5D11R3F-1-GP
R41
5D11R3F-1-GP
1 2
R15 
2K2R2F-GP 
R15 
2K2R2F-GP 
1 2
R12
470R2F-GP
DY
R12
470R2F-GP
DY
1 2
R23 0R2J-2-GPR23 0R2J-2-GP1 2
C58
SCD01U50V2KX-1GP
C58
SCD01U50V2KX-1GP
1 2
R30 
220R2F-GP 
R30 
220R2F-GP 
1 2
TP52 TPAD32-GPTP52 TPAD32-GP1
L57
MPZ1608S331A-GP
L57
MPZ1608S331A-GP
1 2
TP31TPAD32-GP TP31TPAD32-GP 1
TP58 TPAD32-GPTP58 TPAD32-GP1
TP34 TPAD32-GPTP34 TPAD32-GP
1
L58
MPZ1608S331A-GP
L58
MPZ1608S331A-GP
1 2
C64 
SCD01U50V2KX-1GP 
C64 
SCD01U50V2KX-1GP 
1 2
R129 0R2J-2-GPR129 0R2J-2-GP1 2
R26
470R2F-GP
DYR26
470R2F-GP
DY
1 2
TP13TPAD32-GP TP13TPAD32-GP 1
R31 
220R2F-GP 
R31 
220R2F-GP 
1 2
C61 
SCD01U50V2KX-1GP 
C61 
SCD01U50V2KX-1GP 
1 2
TP39TPAD32-GP TP39TPAD32-GP 1
R112
0R2J-2-GP
R112
0R2J-2-GP
1 2
TP12 TPAD32-GPTP12 TPAD32-GP1
R32 
220R2F-GP 
R32 
220R2F-GP 
1 2
TP30 TPAD32-GPTP30 TPAD32-GP1
R21 
4K7R2F-GP 
DY R21 
4K7R2F-GP 
DY 
1 2
TP61 TPAD32-GPTP61 TPAD32-GP1
R33
5D11R3F-1-GP
R33
5D11R3F-1-GP
1 2
TP37TPAD32-GP TP37TPAD32-GP 1
TP63 TPAD32-GPTP63 TPAD32-GP1
R114 0R2J-2-GPR114 0R2J-2-GP1 2
R20 
4K7R2F-GP 
DY R20 
4K7R2F-GP 
DY 
1 2
R43
0R2J-2-GP
R43
0R2J-2-GP
1 2
TP28 TPAD32-GPTP28 TPAD32-GP1
TP35TPAD32-GP TP35TPAD32-GP 1
R39
10KR2F-2-GP
DY
R39
10KR2F-2-GP
DY
1 2
TP18TPAD32-GP TP18TPAD32-GP 1
TP10 TPAD32-GPTP10 TPAD32-GP1
C63 
SC2D2U6D3V3MX-1-GP 
C63 
SC2D2U6D3V3MX-1-GP 
1 2
R18 
4K7R2F-GP 
DY R18 
4K7R2F-GP 
DY 
1 2
R27 
220R2F-GP 
R27 
220R2F-GP 
1 2
TP36 TPAD32-GPTP36 TPAD32-GP
1
TP22 TPAD32-GPTP22 TPAD32-GP1
TP60 TPAD32-GPTP60 TPAD32-GP1
R36
4K75R2F-1-GP
R36
4K75R2F-1-GP
1 2
TP56 TPAD32-GPTP56 TPAD32-GP1
R19 
4K7R2F-GP 
R19 
4K7R2F-GP 
1 2
TP23 TPAD32-GPTP23 TPAD32-GP1
TP33TPAD32-GP TP33TPAD32-GP 1
TP20 TPAD32-GPTP20 TPAD32-GP1
TP9TPAD32-GP TP9TPAD32-GP 1
TP73 TPAD32-GPTP73 TPAD32-GP1
TP75TPAD32-GP TP75TPAD32-GP 1
R40
220R2F-GP
R40
220R2F-GP
1 2
R13 
2K2R2F-GP 
R13 
2K2R2F-GP 
1 2
C62 SC10U6D3V5KX-4GP C62 SC10U6D3V5KX-4GP 
1 2
TP11TPAD32-GP TP11TPAD32-GP 1
TP24 TPAD32-GPTP24 TPAD32-GP1
TP6 TPAD32-GPTP6 TPAD32-GP1
R14 
2K2R2F-GP 
DY R14 
2K2R2F-GP 
DY 
1 2
TP67 TPAD32-GPTP67 TPAD32-GP1R35
4K75R2F-1-GP
DY 
R35
4K75R2F-1-GP
DY 
1 2
TP21TPAD32-GP TP21TPAD32-GP 1
R11
470R2F-GP
DYR11
470R2F-GP
DY
1 2
LED1
LED-G-203-GP
DY
LED1
LED-G-203-GP
DY
A K
R24
75R2F-2-GP
R24
75R2F-2-GP
1 2
TP29TPAD32-GP TP29TPAD32-GP 1
TP26 TPAD32-GPTP26 TPAD32-GP1
TP27TPAD32-GP TP27TPAD32-GP 1
R16 0R2J-2-GPR16 0R2J-2-GP1 2
R22 
4K7R2F-GP 
DY R22 
4K7R2F-GP 
DY 
1 2
TP77TPAD32-GP TP77TPAD32-GP 1
C60 
SC2D2U6D3V3MX-1-GP 
C60 
SC2D2U6D3V3MX-1-GP 
1 2
C66 
SC2D2U6D3V3MX-1-GP 
C66 
SC2D2U6D3V3MX-1-GP 
1 2
R29 
220R2F-GP 
R29 
220R2F-GP 
1 2
R28 
220R2F-GP 
DY R28 
220R2F-GP 
DY 
1 2
LED3
LED-G-203-GP
DYLED3
LED-G-203-GP
DY
A K
LED2
LED-G-203-GP
DYLED2
LED-G-203-GP
DY
AK
C67 
SCD01U50V2KX-1GP 
C67 
SCD01U50V2KX-1GP 
1 2
TP74TPAD32-GP TP74TPAD32-GP 1
R34
5D11R3F-1-GP
R34
5D11R3F-1-GP
1 2
TP17 TPAD32-GPTP17 TPAD32-GP1
TP16 TPAD32-GPTP16 TPAD32-GP1
TP7TPAD32-GP TP7TPAD32-GP 1
TP72 TPAD32-GPTP72 TPAD32-GP1
R130 0R2J-2-GPR130 0R2J-2-GP1 2
TP62 TPAD32-GPTP62 TPAD32-GP1
L56
MPZ1608S331A-GP
L56
MPZ1608S331A-GP
1 2
LED4
LED-G-203-GP
DYLED4
LED-G-203-GP
DY
A K
TP76 TPAD32-GPTP76 TPAD32-GP1
TP25TPAD32-GP TP25TPAD32-GP 1
2 OF 7
Configuration
and GPIO
LEDS
JTAG and Test Pins
U1B
LSISAS2X28-62148B1-1-GP
2 OF 7
Configuration
and GPIO
LEDS
JTAG and Test Pins
U1B
LSISAS2X28-62148B1-1-GP
RESET#AE28
CPUMODE1AG2
CPUMODE0AF2
FSEL1AA6
FSEL0AB6
BLINK_INL21
GPIO0AG1 GPIO1AF1 GPIO2AD4 GPIO3AA7 GPIO4AE1 GPIO5AD3 GPIO6AB5 GPIO7AC4 GPIO8A26 GPIO9B26 GPIO10AH24
SIO_CLKINC1
SIO_DINM10
SIO_LOADINK5
ADC0L8
ADC1J9
OSCAC28
EXPACTIVER26
SXPACTIVER20
IDDTAF4
TN#AH3
SCAN_ENABLEAH5
TCKAF5
TDIAF3
TMSAE5
TRST#AH2
ICE_TCKJ2
ICE_TDIR6
ICE_TMSP10
ICE_TRST#G1
TDIODE_PK10
REF_PLL_CENTER_VDDL18
REF_PLL_VDDV21
REF_PLL_DOWN_VDDK21
INTERLEAVE_EN AC6
ARM_RESET AD5
BLINK_OUT G25
SIO_CLKOUT B1
SIO_DOUT L6
SIO_LOADOUT M9
LED0# AA23LED1# AC23LED2# Y22LED3# W23LED4# AC24LED5# AD24LED6# AC25LED7# U20LED8# AB25LED9# AF26LED10# V22LED11# AC26LED12# AB26LED13# AA26LED14# AB27LED15# U23LED16# U26LED17# AG28LED18# R22LED19# R21LED20# W28LED21# U28LED22# T28LED23# L28LED24# N25LED25# K28LED26# L27LED27# N22TEST_MUX28 G27TEST_MUX29 E27TEST_MUX30 M26TEST_MUX31 E26TEST_MUX32 L24TEST_MUX33 J25TEST_MUX34 K22TEST_MUX35 K25
PROCMON AG5
ADCTP H7
PROCMON_SUPPORT_CELL AH4
TDO AE4
ICE_TDO E1
ICE_RTCK M3
TDIODE_VSS H8
REF_PLL_CENTER_VSS K19
REF_PLL_VSS V20
REF_PLL_DOWN_VSS J22
NC#H24H24
NC#H23H23
NC#K24K24
NC#L22L22
NC#F26F26
NC#K26K26
EF_MDCN21
EF_MDIOL26
LED63#E28
LED62#G28
LED61#H28
LED60#P21
LED59#N26
LED58#P27
LED57#M25
LED56#P26
LED55#T27
LED54#T26
LED53#W27
LED52#Y27
LED51#T21
LED50#AC27
LED49#AE27
LED48#U22
LED47#Y26
LED46#AG26
LED45#AH26
LED44#Y25
LED43#V23
LED42#AF25
LED41#AA24
LED40#AE24
LED39#W22
LED38#Y20
LED37#AB23
LED36#W20
NC#F25 F25
NC#J24 J24
NC#J23 J23
NC#L25 L25
NC#G26 G26
NC#J26 J26
NC#M24 M24
NC#D27 D27
LED99# H27
LED98# N23
LED97# K27
LED96# N27
LED95# N28
LED94# P28
LED93# P24
LED92# P25
LED91# Y28
LED90# U27
LED89#R23
LED88#AF28
LED87#T25
LED86#V26
LED85#W26
LED84#T24
LED83#AF27
LED82#AD26
LED81#U21
LED80#AE26
LED79#V24
LED78#W24
LED77#Y24
LED76#AB24
LED75#AA21
LED74#Y23
LED73#W21
LED72#Y21
TP14 TPAD32-GPTP14 TPAD32-GP1
R10
27KR2F-L-GP
R10
27KR2F-L-GP
1 2
TP66 TPAD32-GPTP66 TPAD32-GP1
TP54 TPAD32-GPTP54 TPAD32-GP1
C59 SC10U6D3V5KX-4GP C59 SC10U6D3V5KX-4GP 
1 2
TP15TPAD32-GP TP15TPAD32-GP 1
R38 220R2F-GPR38 220R2F-GP1 2
C65 SC10U6D3V5KX-4GP C65 SC10U6D3V5KX-4GP 
1 2
TP38 TPAD32-GPTP38 TPAD32-GP
1
TP8 TPAD32-GPTP8 TPAD32-GP1
R42 
220R2F-GP 
DY R42 
220R2F-GP 
DY 
1 2
R17 
4K7R2F-GP 
DY R17 
4K7R2F-GP 
DY 
1 2
TP2TPAD32-GP TP2TPAD32-GP 1
TP19TPAD32-GP TP19TPAD32-GP 1



5
5
4
4
3
3
2
2
1
1
D D
C C
B B
A A
I2C PULL UP
EXPANDER I2C and XMEM I/F
SAS_I2C_A_SDA
SAS_I2C_B_SDA
SAS_I2C_C_SDA
SAS_I2C_D_SDA
SAS_I2C_A_SCL
SAS_I2C_B_SCL
SAS_I2C_C_SCL
SAS_I2C_D_SCL
SAS_SEP_DBINT
SAS_SEP_ERRINT
SAS_SDBTXSAS_SDBRX
SAS_SMART_TXSAS_SMART_RX
SAS_LPC_LRESET#
SAS_LPC_LCLK
SAS_LPC_LAD3
SAS_LPC_LAD2
SAS_LPC_LAD1
SAS_LPC_LAD0
SAS_LPC_SERIRQ
SAS_EPP_DATA7
SAS_EPP_DATA6
SAS_EPP_DATA5
SAS_EPP_DATA4
SAS_EPP_DATA3
SAS_EPP_DATA2
SAS_EPP_DATA1
SAS_EPP_DATA0
SAS_EPP_D_STROBE#
SAS_EPP_A_STROBE#
SAS_EPP_WRITE#
SAS_EPP_RESET#
SAS_MII_COL
SAS_MII_CRS
SAS_MII_MDIO
SAS_MII_RXCLK
SAS_MII_RXD3
SAS_MII_RXD2
SAS_MII_RXD1
SAS_MII_RXD0
SAS_MII_RXDV
SAS_MII_RXER
SAS_MII_TXCLK
SAS_MII_TXER
SAS_XMEM_MAD31
SAS_XMEM_MAD30
SAS_XMEM_MAD29
SAS_XMEM_MAD28
SAS_XMEM_MAD27
SAS_XMEM_MAD26
SAS_XMEM_MAD25
SAS_XMEM_MAD24
SAS_XMEM_MAD23
SAS_XMEM_MAD22
SAS_XMEM_MAD21
SAS_XMEM_MAD20
SAS_XMEM_MAD19
SAS_XMEM_MAD18
SAS_XMEM_MAD17
SAS_XMEM_MAD16
SAS_XMEM_MAD15
SAS_XMEM_MAD14
SAS_XMEM_MAD13
SAS_XMEM_MAD12
SAS_XMEM_MAD11
SAS_XMEM_MAD10
SAS_XMEM_MAD9
SAS_XMEM_MAD8
SAS_XMEM_MAD7
SAS_XMEM_MAD6
SAS_XMEM_MAD5
SAS_XMEM_MAD4
SAS_XMEM_MAD3
SAS_XMEM_MAD2
SAS_XMEM_MAD1
SAS_XMEM_MAD0
SAS_XMEM_MADP3
SAS_XMEM_MAD1
SAS_XMEM_MAD2
SAS_XMEM_MAD12
SAS_XMEM_MAD13
SAS_XMEM_MAD14
SAS_XMEM_MAD15
SAS_XMEM_MAD16
SAS_XMEM_MAD17
SAS_XMEM_MAD18
SAS_XMEM_MAD3
SAS_XMEM_MAD4
SAS_XMEM_MAD5
SAS_XMEM_MAD6
SAS_XMEM_MAD7
SAS_XMEM_MAD8
SAS_XMEM_MAD9
SAS_XMEM_MAD10
SAS_XMEM_MAD11
SAS_XMEM_MAD19
SAS_XMEM_MAD20
SAS_XMEM_MAD21
SAS_XMEM_MAD22
SAS_XMEM_MAD23
SAS_XMEM_MAD24
SAS_XMEM_MAD25
SAS_XMEM_MAD26
SAS_XMEM_MAD27
SAS_XMEM_MAD28
SAS_XMEM_MAD29
SAS_XMEM_MAD30
SAS_XMEM_MAD31
SAS_XMEM_MAD0
SAS_XMEM_MADP0
SAS_XMEM_MADP1
SAS_DBGMODE
SAS_XMEM_MADP2
SAS_XMEM_BWE3
SAS_MII_TXEN
SAS_XMEM_NVSRAM_CS1#
SAS_EPP_WAIT#
SAS_XMEM_MLK
SAS_SEP_OUTRST
SAS_XMEM_ADV#
SAS_XMEM_NVSRAM_CS0#
SAS_XMEM_MWE0#
SAS_XMEM_BWE0
SAS_EPP_INT
SAS_XMEM_ADSC#
SAS_MII_TXD1
SAS_XMEM_MWE1#
SAS_XMEM_OE1#
SAS_XMEM_BWE1
SAS_MII_MDC
SAS_XMEM_FLASH_CS#
SAS_MII_TXD0
SAS_MII_TXD2
SAS_XMEM_OE0#
SAS_XMEM_BWE2
SAS_MII_TXD3
SAS_XMEM_PBSRAM_CS#
SAS_LPC_LFRAME#
3D3V
3D3V
3D3V
SAS_I2C_A_SDA 13
SAS_I2C_B_SDA 14
SAS_I2C_C_SDA 14
SAS_I2C_D_SDA 14
SAS_I2C_A_SCL13
SAS_I2C_B_SCL14
SAS_I2C_C_SCL14
SAS_I2C_D_SCL14
SAS_SDBTX 15SAS_SDBRX15
SAS_SMART_TX 15SAS_SMART_RX15
SAS_XMEM_MAD[31:0]9
SAS_XMEM_MADP39
SAS_XMEM_MADP29
SAS_XMEM_MADP19
SAS_XMEM_MADP09
SAS_XMEM_MLK_PBSRAM 9
SAS_I2C_A_SCL13
SAS_I2C_B_SCL14
SAS_I2C_C_SCL14
SAS_I2C_D_SCL14
SAS_I2C_A_SDA13
SAS_I2C_B_SDA14
SAS_I2C_C_SDA14
SAS_I2C_D_SDA14
SAS_XMEM_ADSC# 9
SAS_XMEM_ADV# 9
SAS_XMEM_BWE3 9
SAS_XMEM_BWE2 9
SAS_XMEM_BWE1 9
SAS_XMEM_BWE0 9
SAS_XMEM_OE0# 9
SAS_XMEM_OE1# 9
SAS_XMEM_MWE0# 9
SAS_XMEM_PBSRAM_CS# 9
SAS_XMEM_FLASH_CS# 9
Title
Size Document Number Rev
Date: Sheet
of
Honey_Badger_SEB 1
SAS2x28 MEMORIES
A3
6 22Tuesday, April 07, 2015
Wiwynn
H/W R&D Dept. II
8F,90,Sec. 1,Hsin Tai Wu Rd,
Hsichih, Taipei Hsien 221, Taiwan, R.O.C
Title
Size Document Number Rev
Date: Sheet
of
Honey_Badger_SEB 1
SAS2x28 MEMORIES
A3
6 22Tuesday, April 07, 2015
Wiwynn
H/W R&D Dept. II
8F,90,Sec. 1,Hsin Tai Wu Rd,
Hsichih, Taipei Hsien 221, Taiwan, R.O.C
Title
Size Document Number Rev
Date: Sheet
of
Honey_Badger_SEB 1
SAS2x28 MEMORIES
A3
6 22Tuesday, April 07, 2015
Wiwynn
H/W R&D Dept. II
8F,90,Sec. 1,Hsin Tai Wu Rd,
Hsichih, Taipei Hsien 221, Taiwan, R.O.C
R78 4K75R2F-1-GPDY R78 4K75R2F-1-GPDY 1 2
R50 
10KR2F-2-GP 
R50 
10KR2F-2-GP 
1 2
R58 4K75R2F-1-GPDY R58 4K75R2F-1-GPDY 1 2
TP105 TPAD32-GPTP105 TPAD32-GP1
TP106 TPAD32-GPTP106 TPAD32-GP1
TP88 TPAD32-GPTP88 TPAD32-GP1
TP102 TPAD32-GPTP102 TPAD32-GP1
TP84 TPAD32-GPTP84 TPAD32-GP1
R57 4K75R2F-1-GPDY R57 4K75R2F-1-GPDY 1 2
R82 4K75R2F-1-GPDY R82 4K75R2F-1-GPDY 1 2
R63 4K75R2F-1-GPDY R63 4K75R2F-1-GPDY 1 2
TP114 TPAD32-GPTP114 TPAD32-GP1
TP89TPAD32-GP TP89TPAD32-GP 1
R44 
1KR2F-3-GP 
R44 
1KR2F-3-GP 
1 2
TP92TPAD32-GP TP92TPAD32-GP 1
TP91TPAD32-GP TP91TPAD32-GP 1
R86 4K75R2F-1-GPDY R86 4K75R2F-1-GPDY 1 2
R67 4K75R2F-1-GPDY R67 4K75R2F-1-GPDY 1 2
TP110TPAD32-GP TP110TPAD32-GP 1
R70 
220R2F-GP 
DY R70 
220R2F-GP 
DY 
1 2
R73 4K75R2F-1-GPDY R73 4K75R2F-1-GPDY 1 2
TP95TPAD32-GP TP95TPAD32-GP 1
TP82 TPAD32-GPTP82 TPAD32-GP1
TP90 TPAD32-GPTP90 TPAD32-GP1
TP116 TPAD32-GPTP116 TPAD32-GP1
TP99TPAD32-GP TP99TPAD32-GP 1
R77 4K75R2F-1-GPDY R77 4K75R2F-1-GPDY 1 2
R51 
10KR2F-2-GP 
R51 
10KR2F-2-GP 
1 2
TP115TPAD32-GP TP115TPAD32-GP 1
R47 
10KR2F-2-GP 
R47 
10KR2F-2-GP 
1 2
TP121TPAD32-GP TP121TPAD32-GP 1
TP98TPAD32-GP TP98TPAD32-GP 1
TP87TPAD32-GP TP87TPAD32-GP 1
R81 4K75R2F-1-GPDY R81 4K75R2F-1-GPDY 1 2
R61 4K75R2F-1-GPDY R61 4K75R2F-1-GPDY 1 2
TP101TPAD32-GP TP101TPAD32-GP 1
TP124 TPAD32-GPTP124 TPAD32-GP1
TP93TPAD32-GP TP93TPAD32-GP 1
TP123TPAD32-GP TP123TPAD32-GP 1
R53 4K75R2F-1-GPDY R53 4K75R2F-1-GPDY 1 2
R80 4K75R2F-1-GPDY R80 4K75R2F-1-GPDY 1 2
TP120TPAD32-GP TP120TPAD32-GP 1
R85 4K75R2F-1-GPDY R85 4K75R2F-1-GPDY 1 2
R66 4K75R2F-1-GPDY R66 4K75R2F-1-GPDY 1 2
TP107 TPAD32-GPTP107 TPAD32-GP1
R71 4K75R2F-1-GPDY R71 4K75R2F-1-GPDY 1 2
R46 
10KR2F-2-GP 
R46 
10KR2F-2-GP 
1 2
TP122 TPAD32-GPTP122 TPAD32-GP1
TP111TPAD32-GP TP111TPAD32-GP 1
TP100 TPAD32-GPTP100 TPAD32-GP1
R76 4K75R2F-1-GPDY R76 4K75R2F-1-GPDY 1 2
TP103TPAD32-GP TP103TPAD32-GP 1
R54 4K75R2F-1-GPDY R54 4K75R2F-1-GPDY 1 2
R52 4K75R2F-1-GPDY R52 4K75R2F-1-GPDY 1 2
TP97TPAD32-GP TP97TPAD32-GP 1
TP125TPAD32-GP TP125TPAD32-GP 1
R48 
10KR2F-2-GP 
R48 
10KR2F-2-GP 
1 2
R60 4K75R2F-1-GPDY R60 4K75R2F-1-GPDY 1 2
TP119TPAD32-GP TP119TPAD32-GP 1
R84 4K75R2F-1-GPDY R84 4K75R2F-1-GPDY 1 2
TP85 TPAD32-GPTP85 TPAD32-GP1
R65 4K75R2F-1-GPDY R65 4K75R2F-1-GPDY 1 2
R69 4K75R2F-1-GPDY R69 4K75R2F-1-GPDY 1 2
TP108TPAD32-GP TP108TPAD32-GP 1
TP86TPAD32-GP TP86TPAD32-GP 1
TP83 TPAD32-GPTP83 TPAD32-GP1
TP94TPAD32-GP TP94TPAD32-GP 1
R75 4K75R2F-1-GPDY R75 4K75R2F-1-GPDY 1 2
1 OF 7
Serial Port
LPC Interface
Parallel
Debug Port
External
Memory
External
Phy
Ethernet Mll
U1A
LSISAS2X28-62148B1-1-GP
1 OF 7
Serial Port
LPC Interface
Parallel
Debug Port
External
Memory
External
Phy
Ethernet Mll
U1A
LSISAS2X28-62148B1-1-GP
ASCLN5
BSCLE2
CSCLP9
SEP_SCLN8
SDBRXF1
RXDN4
LPC_LAD3F3
LPC_LAD2K4
LPC_LAD1G4
LPC_LAD0N9
LPC_SERIRQH3
EPP_DATA7Y5
EPP_DATA6Y4
EPP_DATA5V8
EPP_DATA4V9
EPP_DATA3AB2
EPP_DATA2AB3
EPP_DATA1AC1
EPP_DATA0AB4
EPP_ADDRSTROBE#V10
EPP_DATASTROBE#W8
EPP_WRITE#AC2
EPP_RESET#AD1
DBGMODEAD2
MAD31T1
MAD30P1
MAD29T10
MAD28U7
MAD27R1
MAD26T4
MAD25T3
MAD24W1
MAD23V1
MAD22T2
MAD21T9
MAD20T6
MAD19U1
MAD18Y1
MAD17U5
MAD16V2
MAD15U6
MAD14U4
MAD13U8
MAD12V6
MAD11AA1
MAD10AB1
MAD9V5
MAD8W5
MAD7W2
MAD6V4
MAD5V7
MAD4U9
MAD3V3
MAD2Y2
MAD1Y3
MAD0AA4
MADP3L1
MADP2M1
MADP1N1
MADP0T5
MII_COLM7
MII_CRSM6
MII_MDIOK6
MII_RXCLKG5
MII_RXD3A2
MII_RXD2D3
MII_RXD1E3
MII_RXD0F4
MII_RXDVK7
MII_RXERG6
MII_TXCLKH6
BWE3# M2
BWE2# K1
BWE1# R2
BWE0# R3
MOE0# H1
MOE1# R9
MWE0# R10
MWE1# P4
NVSRAM_CS0# P5
NVSRAM_CS1# P6
PBSRAM_CS# J1
FLASH_CS# P3
MII_MDC H5
MII_TXD3 B3
MII_TXD2 J7
MII_TXD1 C3
MII_TXD0 A3
MII_TXEN L7
MII_TXER J6
ASDA M4
BSDA N6
CSDA D1
SEP_SDA N7
SEP_DBINT J3
SEP_ERRINT L4
SEP_OUTRST K3
SDBTX L3
TXD H2
LPC_LFRAME# G3
LPC_LRESET# H4
LPC_LCLK M8
EPP_INTERRUPT AA5
EPP_WAIT# Y6
MCLK R7
ADSC# R8
ADV# P2
R56 4K75R2F-1-GPDY R56 4K75R2F-1-GPDY 1 2
R79 4K75R2F-1-GPDY R79 4K75R2F-1-GPDY 1 2
R59 4K75R2F-1-GPDY R59 4K75R2F-1-GPDY 1 2
TP104TPAD32-GP TP104TPAD32-GP 1
TP80TPAD32-GP TP80TPAD32-GP 1
R72 22D1R2F-GPR72 22D1R2F-GP1 2
R49 
10KR2F-2-GP 
R49 
10KR2F-2-GP 
1 2
TP113TPAD32-GP TP113TPAD32-GP 1
TP96TPAD32-GP TP96TPAD32-GP 1
R83 4K75R2F-1-GPDY R83 4K75R2F-1-GPDY 1 2
R64 4K75R2F-1-GPDY R64 4K75R2F-1-GPDY 1 2
TP117TPAD32-GP TP117TPAD32-GP 1
R55 4K75R2F-1-GPDY R55 4K75R2F-1-GPDY 1 2
TP109 TPAD32-GPTP109 TPAD32-GP1
R68 4K75R2F-1-GPDY R68 4K75R2F-1-GPDY 1 2
TP118 TPAD32-GPTP118 TPAD32-GP1
R62 
4K75R2F-1-GP 
R62 
4K75R2F-1-GP 
1 2
TP112 TPAD32-GPTP112 TPAD32-GP1
TP81TPAD32-GP TP81TPAD32-GP 1
R45 
1KR2F-3-GP 
R45 
1KR2F-3-GP 
1 2
R74 4K75R2F-1-GPDY R74 4K75R2F-1-GPDY 1 2



5
5
4
4
3
3
2
2
1
1
D D
C C
B B
A A
SAS_ADC_VDDIO33
1V
1V
3D3V
3D3V
3D3V
3D3V
Title
Size Document Number Rev
Date: Sheet
of
Honey_Badger_SEB 1
SAS2x28 POWER&GND
A3
7 22Tuesday, April 07, 2015
Wiwynn
H/W R&D Dept. II
8F,90,Sec. 1,Hsin Tai Wu Rd,
Hsichih, Taipei Hsien 221, Taiwan, R.O.C
Title
Size Document Number Rev
Date: Sheet
of
Honey_Badger_SEB 1
SAS2x28 POWER&GND
A3
7 22Tuesday, April 07, 2015
Wiwynn
H/W R&D Dept. II
8F,90,Sec. 1,Hsin Tai Wu Rd,
Hsichih, Taipei Hsien 221, Taiwan, R.O.C
Title
Size Document Number Rev
Date: Sheet
of
Honey_Badger_SEB 1
SAS2x28 POWER&GND
A3
7 22Tuesday, April 07, 2015
Wiwynn
H/W R&D Dept. II
8F,90,Sec. 1,Hsin Tai Wu Rd,
Hsichih, Taipei Hsien 221, Taiwan, R.O.C
C92 
SCD047U16V2ZY-1GP 
C92 
SCD047U16V2ZY-1GP 
1 2
C86 
SCD01U50V2KX-1GP 
C86 
SCD01U50V2KX-1GP 
1 2
C101 
SCD022U16V2KX-3GP 
C101 
SCD022U16V2KX-3GP 
1 2
C94 
SCD022U16V2KX-3GP 
C94 
SCD022U16V2KX-3GP 
1 2
C112 
SCD1U16V2KX-3GP 
C112 
SCD1U16V2KX-3GP 
1 2
C106 SC10U6D3V5KX-4GP C106 SC10U6D3V5KX-4GP 
1 2
C104 
SCD1U16V2KX-3GP 
C104 
SCD1U16V2KX-3GP 
1 2
C79 
SCD01U50V2KX-1GP 
C79 
SCD01U50V2KX-1GP 
1 2
C81 
SCD01U50V2KX-1GP 
C81 
SCD01U50V2KX-1GP 
1 2
C114 
SCD1U16V2KX-3GP 
C114 
SCD1U16V2KX-3GP 
1 2
C91 
SCD047U16V2ZY-1GP 
C91 
SCD047U16V2ZY-1GP 
1 2
C87 
SCD01U50V2KX-1GP 
C87 
SCD01U50V2KX-1GP 
1 2
C125 
SCD01U50V2KX-1GP 
C125 
SCD01U50V2KX-1GP 
1 2
C119 
SCD01U50V2KX-1GP 
C119 
SCD01U50V2KX-1GP 
1 2
C118 
SCD01U50V2KX-1GP 
C118 
SCD01U50V2KX-1GP 
1 2
C110 
SCD1U16V2KX-3GP 
C110 
SCD1U16V2KX-3GP 
1 2
C100 
SCD022U16V2KX-3GP 
C100 
SCD022U16V2KX-3GP 
1 2
R87
2D2R3J-2-GP
R87
2D2R3J-2-GP
1 2
C97 
SCD022U16V2KX-3GP 
C97 
SCD022U16V2KX-3GP 
1 2
C121 
SCD01U50V2KX-1GP 
C121 
SCD01U50V2KX-1GP 
1 2
C82 
SCD01U50V2KX-1GP 
C82 
SCD01U50V2KX-1GP 
1 2
C122 
SCD01U50V2KX-1GP 
C122 
SCD01U50V2KX-1GP 
1 2
C123 
SCD01U50V2KX-1GP 
C123 
SCD01U50V2KX-1GP 
1 2
C117 
SCD1U16V2KX-3GP 
C117 
SCD1U16V2KX-3GP 
1 2
C98 
SCD022U16V2KX-3GP 
C98 
SCD022U16V2KX-3GP 
1 2
C103 
SCD1U16V2KX-3GP 
C103 
SCD1U16V2KX-3GP 
1 2
C95 
SCD022U16V2KX-3GP 
C95 
SCD022U16V2KX-3GP 
1 2
C75 
SCD22U6D3V2KX-1GP 
C75 
SCD22U6D3V2KX-1GP 
1 2
C120 
SCD01U50V2KX-1GP 
C120 
SCD01U50V2KX-1GP 
1 2
C69 SC4D7U10V3KX-GP C69 SC4D7U10V3KX-GP 
1 2
5 OF 7
Core Power
Standard I/O Power 3.3V 
1V
U1E
LSISAS2X28-62148B1-1-GP
5 OF 7
Core Power
Standard I/O Power 3.3V 
1V
U1E
LSISAS2X28-62148B1-1-GP
VDDN13
VDDN15
VDDN17
VDDP12
VDDP14
VDDP16
VDDR13
VDD R15
VDD R17
VDD T12
VDD T14
VDD T16
VDD V11
ADC_VDDIO33 K9
ADC_VDDIO33 L9
ADC_VDDIO33 L10
VDDIO33C2
VDDIO33D2
VDDIO33F27
VDDIO33G2
VDDIO33H25
VDDIO33J5
VDDIO33J27
VDDIO33K23
VDDIO33L2
VDDIO33M5
VDDIO33M19
VDDIO33M20
VDDIO33M27
VDDIO33N2
VDDIO33N10
VDDIO33N24
VDDIO33P7
VDDIO33P11
VDDIO33P18
VDDIO33P19
VDDIO33P20
VDDIO33P22
VDDIO33R4
VDDIO33R11
VDDIO33R19
VDDIO33R24
VDDIO33R27
VDDIO33T7
VDDIO33T11
VDDIO33 T18
VDDIO33 T19
VDDIO33 T22
VDDIO33 U2
VDDIO33 U10
VDDIO33 U19
VDDIO33 U24
VDDIO33 U25
VDDIO33 V12
VDDIO33 V25
VDDIO33 V27
VDDIO33 W4
VDDIO33 W6
VDDIO33 W9
VDDIO33 W10
VDDIO33 W11
VDDIO33 W19
VDDIO33 Y8
VDDIO33 AA2
VDDIO33 AA22
VDDIO33 AA27
VDDIO33 AB28
VDDIO33 AC5
VDDIO33 AD25
VDDIO33 AD27
VDDIO33 AE2
VDDIO33 AG4
VDDIO33 AG27
VDDIO33 AG24
C102 
SCD1U16V2KX-3GP 
C102 
SCD1U16V2KX-3GP 
1 2C84 
SCD01U50V2KX-1GP 
C84 
SCD01U50V2KX-1GP 
1 2
L59
MPZ1608S331A-GP
L59
MPZ1608S331A-GP
1 2
C72 
SC1U10V2KX-4-GP 
C72 
SC1U10V2KX-4-GP 
1 2
C113 
SCD1U16V2KX-3GP 
C113 
SCD1U16V2KX-3GP 
1 2
C90 
SCD047U16V2ZY-1GP 
C90 
SCD047U16V2ZY-1GP 
1 2
C115 
SCD1U16V2KX-3GP 
C115 
SCD1U16V2KX-3GP 
1 2
C105 
SCD1U16V2KX-3GP 
C105 
SCD1U16V2KX-3GP 
1 2
C77 
SCD01U50V2KX-1GP 
C77 
SCD01U50V2KX-1GP 
1 2
C68 SC4D7U10V3KX-GP C68 SC4D7U10V3KX-GP 
1 2
C89 
SCD047U16V2ZY-1GP 
C89 
SCD047U16V2ZY-1GP 
1 2
C111 
SCD1U16V2KX-3GP 
C111 
SCD1U16V2KX-3GP 
1 2
C107 
SCD01U50V2KX-1GP 
C107 
SCD01U50V2KX-1GP 
1 2
TC1 
ST330U2D5VDM-9GP 
TC1 
ST330U2D5VDM-9GP 
1 2
C109 
SC1U10V2KX-4-GP 
C109 
SC1U10V2KX-4-GP 
1 2
C88 
SCD047U16V2ZY-1GP 
C88 
SCD047U16V2ZY-1GP 
1 2
C83 
SCD47U6D3V2KX-GP 
C83 
SCD47U6D3V2KX-GP 
1 2
C99 
SCD022U16V2KX-3GP 
C99 
SCD022U16V2KX-3GP 
1 2
C78 
SCD01U50V2KX-1GP 
C78 
SCD01U50V2KX-1GP 
1 2
C124 
SCD01U50V2KX-1GP 
C124 
SCD01U50V2KX-1GP 
1 2
TC2 
ST100U6D3VBML1GP 
TC2 
ST100U6D3VBML1GP 
1 2
C85 
SCD01U50V2KX-1GP 
C85 
SCD01U50V2KX-1GP 
1 2
C70 SC4D7U10V3KX-GP C70 SC4D7U10V3KX-GP 
1 2
C76 
SCD22U6D3V2KX-1GP 
C76 
SCD22U6D3V2KX-1GP 
1 2
6 OF 7U1F
LSISAS2X28-62148B1-1-GP
6 OF 7U1F
LSISAS2X28-62148B1-1-GP
VSSA4
VSSA25
VSSA27
VSSB2
VSSB4
VSSB25
VSSB27
VSSC4
VSSC5
VSSC8
VSSC9
VSSC12
VSSC13
VSSC16
VSSC17
VSSC20
VSSC21
VSSC24
VSSC25
VSSC26
VSSC27
VSSD4
VSSD25
VSSD26
VSSD28
VSSE4
VSSE25
VSSF2
VSSF5
VSSF6
VSSF15
VSSF18
VSSF23
VSSF28
VSSG7
VSSG8
VSSG12
VSSG14
VSSG15
VSSG16
VSSG17
VSSG21
VSSG24
VSSH11
VSSH13
VSSH15
VSSH22
VSSH26
VSSJ4
VSSJ8
VSSJ12
VSSJ17
VSSJ19
VSSJ20
VSSJ21
VSSJ28
VSSK2
ADC_VSSIOK8
VSSK20
VSSL5
VSSL11
VSSL19
VSSL20
VSSL23
VSSM11
VSSM18
VSSM21
VSSM28
VSSN3
VSSN11
VSSN12
VSSN14
VSSN16
VSSN18
VSSN20
VSSP8
VSSP13
VSSP15
VSSP17
VSSP23
VSS R5
VSS R12
VSS R14
VSS R16
VSS R18
VSS R25
VSS R28
VSS T8
VSS T13
VSS T15
VSS T17
VSS T20
VSS T23
VSS U3
VSS U11
VSS U12
VSS U18
VSS V19
VSS V28
VSS W3
VSS W7
VSS W12
VSS W18
VSS W25
VSS Y7
VSS Y9
VSS Y10
VSS Y13
VSS Y17
VSS Y19
VSS AA3
VSS AA8
VSS AA14
VSS AA15
VSS AA18
VSS AA20
VSS AA25
VSS AA28
VSS AB7
VSS AB9
VSS AB10
VSS AB12
VSS AB13
VSS AB15
VSS AB16
VSS AB17
VSS AB19
VSS AB21
VSS AB22
VSS AC3
VSS AC8
VSS AC9
VSS AC21
VSS AD6
VSS AD23
VSS AD28
VSS AE3
VSS AE6
VSS AE23
VSS AE25
VSS AF6
VSS AF7
VSS AF10
VSS AF11
VSS AF14
VSS AF15
VSS AF18
VSS AF19
VSS AF22
VSS AF23
VSS AF24
VSS AG3
VSS AG6
VSS AG23
VSS AG25
VSS AH6
VSS AH23
VSS AH25
VSS AH27
C73 
SCD47U6D3V2KX-GP 
C73 
SCD47U6D3V2KX-GP 
1 2
C71 
SC1U10V2KX-4-GP 
C71 
SC1U10V2KX-4-GP 
1 2
C108 
SC2D2U6D3V3MX-1-GP 
C108 
SC2D2U6D3V3MX-1-GP 
1 2
C116 
SCD1U16V2KX-3GP 
C116 
SCD1U16V2KX-3GP 
1 2
C93 
SCD047U16V2ZY-1GP 
C93 
SCD047U16V2ZY-1GP 
1 2
C96 
SCD022U16V2KX-3GP 
C96 
SCD022U16V2KX-3GP 
1 2
C74 
SCD22U6D3V2KX-1GP 
C74 
SCD22U6D3V2KX-1GP 
1 2
C80 
SCD01U50V2KX-1GP 
C80 
SCD01U50V2KX-1GP 
1 2



5
5
4
4
3
3
2
2
1
1
D D
C C
B B
A A
SAS_MXSVDD10_FILT_TOP
SAS_MXSVDD10_FILT_BOTTOM
SAS_MXSVDD10_FILT_BOTTOMSAS_GB_TXVCOVDD
SAS_MXSVDD10_FILT_TOP
1V
1V
1V
1D8V
1V
Title
Size Document Number Rev
Date: Sheet
of
Honey_Badger_SEB 1
SAS2x28 POWER&GND-2
A3
8 22Tuesday, April 07, 2015
Wiwynn
H/W R&D Dept. II
8F,90,Sec. 1,Hsin Tai Wu Rd,
Hsichih, Taipei Hsien 221, Taiwan, R.O.C
Title
Size Document Number Rev
Date: Sheet
of
Honey_Badger_SEB 1
SAS2x28 POWER&GND-2
A3
8 22Tuesday, April 07, 2015
Wiwynn
H/W R&D Dept. II
8F,90,Sec. 1,Hsin Tai Wu Rd,
Hsichih, Taipei Hsien 221, Taiwan, R.O.C
Title
Size Document Number Rev
Date: Sheet
of
Honey_Badger_SEB 1
SAS2x28 POWER&GND-2
A3
8 22Tuesday, April 07, 2015
Wiwynn
H/W R&D Dept. II
8F,90,Sec. 1,Hsin Tai Wu Rd,
Hsichih, Taipei Hsien 221, Taiwan, R.O.C
R89
D51R5F-GP
R89
D51R5F-GP
1 2
C146 
SCD022U16V2KX-3GP 
C146 
SCD022U16V2KX-3GP 
1 2
C135 SC10U6D3V5KX-4GP C135 SC10U6D3V5KX-4GP 
1 2
L62
MPZ1608S331A-GP
L62
MPZ1608S331A-GP
1 2
C155 
SC22U6D3V5MX-2GP 
C155 
SC22U6D3V5MX-2GP 
1 2
C149 SC10U6D3V5KX-4GP C149 SC10U6D3V5KX-4GP 
1 2
L63
MPZ2012S101A-GP
L63
MPZ2012S101A-GP
1 2
C128 
SC22U6D3V5MX-2GP 
C128 
SC22U6D3V5MX-2GP 
1 2
TC4 
ST330U2D5VDM-9GP 
TC4 
ST330U2D5VDM-9GP 
1 2
C154 SC10U6D3V5KX-4GP C154 SC10U6D3V5KX-4GP 
1 2
R90
5D11R3F-1-GP
R90
5D11R3F-1-GP
1 2
C127 SCD47U6D3V2KX-GP C127 SCD47U6D3V2KX-GP 
1 2
C138 
SC1U10V2KX-4-GP 
C138 
SC1U10V2KX-4-GP 
1 2
C157 SC10U6D3V5KX-4GP C157 SC10U6D3V5KX-4GP 
1 2
L61
MPZ2012S101A-GP
L61
MPZ2012S101A-GP
1 2
L64
MPZ2012S101A-GP
L64
MPZ2012S101A-GP
1 2
C159 
SCD01U50V2KX-1GP 
C159 
SCD01U50V2KX-1GP 
1 2
C141 SC4D7U10V3KX-GP C141 SC4D7U10V3KX-GP 
1 2
C156 
SC22U6D3V5MX-2GP 
C156 
SC22U6D3V5MX-2GP 
1 2
C136 
SC2D2U6D3V3MX-1-GP 
C136 
SC2D2U6D3V3MX-1-GP 
1 2
C147 
SCD1U16V2KX-3GP 
C147 
SCD1U16V2KX-3GP 
1 2
TC6 
ST220U6D3VDM-20GP 
TC6 
ST220U6D3VDM-20GP 
1 2
C150 
SC2D2U6D3V3MX-1-GP 
C150 
SC2D2U6D3V3MX-1-GP 
1 2
C133 
SC2D2U6D3V3MX-1-GP 
C133 
SC2D2U6D3V3MX-1-GP 
1 2
C130 
SCD01U50V2KX-1GP 
C130 
SCD01U50V2KX-1GP 
1 2
C145 
SCD22U6D3V2KX-1GP 
C145 
SCD22U6D3V2KX-1GP 
1 2C131 SC4D7U10V3KX-GP C131 SC4D7U10V3KX-GP 
1 2
C140 SC4D7U10V3KX-GP C140 SC4D7U10V3KX-GP 
1 2
C132 
SC1U10V2KX-4-GP 
C132 
SC1U10V2KX-4-GP 
1 2
C144 SC4D7U10V3KX-GP C144 SC4D7U10V3KX-GP 
1 2
7 OF 7U1G
LSISAS2X28-62148B1-1-GP
7 OF 7U1G
LSISAS2X28-62148B1-1-GP
MXS_VDD10C6
MXS_VDD10C7
MXS_VDD10C10
MXS_VDD10C11
MXS_VDD10C14
MXS_VDD10C15
MXS_VDD10C18
MXS_VDD10C19
MXS_VDD10C22
MXS_VDD10C23
MXS_VDD10F8
MXS_VDD10F12
MXS_VDD10F17
MXS_VDD10F21
MXS_VDD10F24
MXS_VDD10G9
MXS_VDD10G10
MXS_VDD10G11
MXS_VDD10G13
MXS_VDD10G18
MXS_VDD10G19
MXS_VDD10G20
MXS_VDD10G22
MXS_VDD10G23
MXS_VDD10H9
MXS_VDD10H10
MXS_VDD10H12
MXS_VDD10H14
MXS_VDD10H16
MXS_VDD10H17
MXS_VDD10H18
MXS_VDD10H19
MXS_VDD10H20
MXS_VDD10H21
MXS_VDD10J10
MXS_VDD10J11
MXS_VDD10J13
MXS_VDD10J14
MXS_VDD10J15
MXS_VDD10J16
MXS_VDD10J18
MXS_VDD10K11
MXS_VDD10K12
MXS_VDD10K13
MXS_VDD10K14
MXS_VDD10K15
MXS_VDD10K16
MXS_VDD10K17
MXS_VDD10K18
MXS_VDD10L12
MXS_VDD10L13
MXS_VDD10 L14
MXS_VDD10 L15
MXS_VDD10 L16
MXS_VDD10 L17
MXS_VDD10 M16
MXS_VDD10 N19
MXS_VDD10 U14
MXS_VDD10 V13
MXS_VDD10 V14
MXS_VDD10 V15
MXS_VDD10 V16
MXS_VDD10 V17
MXS_VDD10 V18
MXS_VDD10 W13
MXS_VDD10 W14
MXS_VDD10 W15
MXS_VDD10 W16
MXS_VDD10 W17
MXS_VDD10 Y11
MXS_VDD10 Y12
MXS_VDD10 Y14
MXS_VDD10 Y15
MXS_VDD10 Y16
MXS_VDD10 Y18
MXS_VDD10 AA9
MXS_VDD10 AA10
MXS_VDD10 AA11
MXS_VDD10 AA12
MXS_VDD10 AA13
MXS_VDD10 AA16
MXS_VDD10 AA17
MXS_VDD10 AA19
MXS_VDD10 AB8
MXS_VDD10 AB11
MXS_VDD10 AB14
MXS_VDD10 AB18
MXS_VDD10 AB20
MXS_VDD10 AC7
MXS_VDD10 AC11
MXS_VDD10 AC15
MXS_VDD10 AC18
MXS_VDD10 AC22
MXS_VDD10 AF8
MXS_VDD10 AF9
MXS_VDD10 AF12
MXS_VDD10 AF13
MXS_VDD10 AF16
MXS_VDD10 AF17
MXS_VDD10 AF20
MXS_VDD10 AF21
GB_TXVCOVDDU15
GB_TXVCOVDDU16
GB_TXVCOVDDU17
GB_TXVCOVDDM17
GB_TXVCOVDDM15
GB_TXVCOVDDM14
GB_TXVCOVDDM13
GB_TXVCOVDDU13
GB_TXVCOVDDM12
GB_TXVTERM#AC13 AC13
GB_TXVTERM#AC16 AC16
GB_TXVTERM#AC19 AC19
GB_TXVTERM#F22 F22
GB_TXVTERM#F19 F19
GB_TXVTERM#F14 F14
GB_TXVTERM#F11 F11
GB_TXVTERM#AC10 AC10
GB_TXVTERM#F9 F9
GB_TXVTERM#AC14AC14
GB_TXVTERM#AC17AC17
GB_TXVTERM#AC20AC20
GB_TXVTERM#F20F20
GB_TXVTERM#F16F16
GB_TXVTERM#F13F13
GB_TXVTERM#F10F10
GB_TXVTERM#AC12AC12
GB_TXVTERM#F7F7
C137 
SCD01U50V2KX-1GP 
C137 
SCD01U50V2KX-1GP 
1 2
C148 
SCD01U50V2KX-1GP 
C148 
SCD01U50V2KX-1GP 
1 2
C153 
SC2D2U6D3V3MX-1-GP 
C153 
SC2D2U6D3V3MX-1-GP 
1 2
TC3 
ST330U2D5VDM-9GP 
TC3 
ST330U2D5VDM-9GP 
1 2
L60
MPZ2012S101A-GP
L60
MPZ2012S101A-GP
1 2
R91
D51R5F-GP
R91
D51R5F-GP
1 2
C151 
SCD01U50V2KX-1GP 
C151 
SCD01U50V2KX-1GP 
1 2
C139 SCD47U6D3V2KX-GP C139 SCD47U6D3V2KX-GP 
1 2
TC5 
ST330U2D5VDM-9GP 
TC5 
ST330U2D5VDM-9GP 
1 2
C129 SC10U6D3V5KX-4GP C129 SC10U6D3V5KX-4GP 
1 2
C143 SCD47U6D3V2KX-GP C143 SCD47U6D3V2KX-GP 
1 2
C134 
SC22U6D3V5MX-2GP 
C134 
SC22U6D3V5MX-2GP 
1 2
R92
D51R5F-GP
R92
D51R5F-GP
1 2
C158 
SC2D2U6D3V3MX-1-GP 
C158 
SC2D2U6D3V3MX-1-GP 
1 2
R88
D51R5F-GP
R88
D51R5F-GP
1 2
C126 
SC4D7U10V3KX-GP 
C126 
SC4D7U10V3KX-GP 
1 2
C142 
SCD047U16V2ZY-1GP 
C142 
SCD047U16V2ZY-1GP 
1 2
C152 
SCD01U50V2KX-1GP 
C152 
SCD01U50V2KX-1GP 
1 2



5
5
4
4
3
3
2
2
1
1
D D
C C
B B
A A
PBSRAM
1Mbits*36
FLASH
8Mbits*8
SAS_XMEM_ADSC#
SAS_XMEM_ADV#
SAS_XMEM_BWE0
SAS_XMEM_BWE3
SAS_XMEM_BWE1
SAS_XMEM_BWE2
SAS_XMEM_OE0#
SAS_XMEM_PBSRAM_CS#
SAS_XMEM_PBSRAM_CS2
SAS_XMEM_PBSRAM_CS2#
SAS_XMEM_MLK_PBSRAM
SAS_XMEM_PBSRAM_ZZ
SAS_XMEM_MAD16
SAS_XMEM_MAD5
SAS_XMEM_MAD15
SAS_XMEM_MAD14
SAS_XMEM_MAD4
SAS_XMEM_MAD13
SAS_XMEM_MAD3
SAS_XMEM_MAD12
SAS_XMEM_MAD2
SAS_XMEM_MAD21
SAS_XMEM_MAD8
SAS_XMEM_MAD20
SAS_XMEM_MAD9
SAS_XMEM_MAD19
SAS_XMEM_MAD10
SAS_XMEM_MAD18
SAS_XMEM_MAD11
SAS_XMEM_MAD7
SAS_XMEM_MAD17
SAS_XMEM_MAD6
SAS_XMEM_MADP0
SAS_XMEM_MADP2
SAS_XMEM_MADP3
SAS_XMEM_MADP1
SAS_XMEM_MAD23
SAS_XMEM_MAD22
SAS_XMEM_MAD21
SAS_XMEM_MAD20
SAS_XMEM_MAD19
SAS_XMEM_MAD18
SAS_XMEM_MAD17
SAS_XMEM_MAD16
SAS_XMEM_MAD8
SAS_XMEM_MAD9
SAS_XMEM_MAD10
SAS_XMEM_MAD11
SAS_XMEM_MAD12
SAS_XMEM_MAD13
SAS_XMEM_MAD14
SAS_XMEM_MAD15
SAS_XMEM_MAD31
SAS_XMEM_MAD25
SAS_XMEM_MAD24
SAS_XMEM_MAD30
SAS_XMEM_MAD29
SAS_XMEM_MAD28
SAS_XMEM_MAD27
SAS_XMEM_MAD26
SAS_XMEM_MAD0
SAS_XMEM_MAD1
SAS_XMEM_MAD2
SAS_XMEM_MAD3
SAS_XMEM_MAD4
SAS_XMEM_MAD5
SAS_XMEM_MAD6
SAS_XMEM_MAD7
SAS_XMEM_MWE0#
SAS_XMEM_GWE#
SAS_XMEM_ADSP#
SAS_XMEM_LBO#
SAS_XMEM_BWE3
SAS_XMEM_MAD1
SAS_XMEM_MAD2
SAS_XMEM_MAD3
SAS_XMEM_MAD4
SAS_XMEM_MAD5
SAS_XMEM_MAD6
SAS_XMEM_MAD7
SAS_XMEM_MAD8
SAS_XMEM_MAD9
SAS_XMEM_MAD10
SAS_XMEM_MAD11
SAS_XMEM_MAD12
SAS_XMEM_MAD13
SAS_XMEM_MAD14
SAS_XMEM_MAD15
SAS_XMEM_MAD16
SAS_XMEM_MAD17
SAS_XMEM_MAD18
SAS_XMEM_MAD19
SAS_XMEM_MAD20
SAS_XMEM_MAD21
SAS_XMEM_MAD22
SAS_XMEM_MAD0
SAS_XMEM_OE1#
SAS_XMEM_FLASH_CS#
SAS_FLASH_DQ14
SAS_FLASH_DQ13
SAS_FLASH_DQ12
SAS_FLASH_DQ11
SAS_FLASH_DQ10
SAS_FLASH_DQ9
SAS_FLASH_DQ8
SAS_XMEM_MAD24
SAS_XMEM_MAD25
SAS_XMEM_MAD26
SAS_XMEM_MAD27
SAS_XMEM_MAD28
SAS_XMEM_MAD29
SAS_XMEM_MAD30
SAS_XMEM_MAD31
RESET IC_RESET#
SAS_FLASH_WP#/ACC
SAS_FLASH_RY/BY#
SAS_FLASH_BYTE#
3D3V
3D3V
3D3V
3D3V
3D3V
3D3V
3D3V
3D3V
3D3V
3D3V
SAS_XMEM_ADSC#6
SAS_XMEM_ADV#6
SAS_XMEM_BWE06
SAS_XMEM_BWE36
SAS_XMEM_BWE16
SAS_XMEM_BWE26
SAS_XMEM_OE0#6
SAS_XMEM_PBSRAM_CS#6
SAS_XMEM_MLK_PBSRAM6
SAS_XMEM_MAD226
SAS_XMEM_MAD216
SAS_XMEM_MAD206
SAS_XMEM_MAD196
SAS_XMEM_MAD186
SAS_XMEM_MAD76
SAS_XMEM_MAD66
SAS_XMEM_MAD56
SAS_XMEM_MAD146
SAS_XMEM_MAD136
SAS_XMEM_MAD126
SAS_XMEM_MAD86
SAS_XMEM_MAD96
SAS_XMEM_MAD106
SAS_XMEM_MAD116
SAS_XMEM_MAD176
SAS_XMEM_MAD166
SAS_XMEM_MAD156
SAS_XMEM_MAD46
SAS_XMEM_MAD36
SAS_XMEM_MAD26
SAS_XMEM_MADP2 6
SAS_XMEM_MADP1 6
SAS_XMEM_MADP0 6
SAS_XMEM_MADP3 6
SAS_XMEM_MAD21 6
SAS_XMEM_MAD20 6
SAS_XMEM_MAD18 6
SAS_XMEM_MAD31 6
SAS_XMEM_MAD6 6
SAS_XMEM_MAD5 6
SAS_XMEM_MAD14 6
SAS_XMEM_MAD13 6
SAS_XMEM_MAD12 6
SAS_XMEM_MAD8 6
SAS_XMEM_MAD9 6
SAS_XMEM_MAD10 6
SAS_XMEM_MAD11 6
SAS_XMEM_MAD17 6
SAS_XMEM_MAD16 6
SAS_XMEM_MAD15 6
SAS_XMEM_MAD4 6
SAS_XMEM_MAD3 6
SAS_XMEM_MAD2 6
SAS_XMEM_MAD22 6
SAS_XMEM_MAD23 6
SAS_XMEM_MAD19 6
SAS_XMEM_MAD30 6
SAS_XMEM_MAD29 6
SAS_XMEM_MAD28 6
SAS_XMEM_MAD27 6
SAS_XMEM_MAD26 6
SAS_XMEM_MAD25 6
SAS_XMEM_MAD24 6
SAS_XMEM_MAD1 6
SAS_XMEM_MAD0 6
SAS_XMEM_MAD7 6
SAS_XMEM_MWE0#6
SAS_XMEM_BWE36
SAS_XMEM_MAD16
SAS_XMEM_OE1#6
SAS_XMEM_FLASH_CS#6
SAS_XMEM_MAD0 6
SAS_XMEM_MAD24 6
SAS_XMEM_MAD25 6
SAS_XMEM_MAD26 6
SAS_XMEM_MAD28 6
SAS_XMEM_MAD29 6
SAS_XMEM_MAD30 6
SAS_XMEM_MAD31 6
SAS_XMEM_MAD27 6
SAS_XMEM_MAD26
SAS_XMEM_MAD36
SAS_XMEM_MAD46
SAS_XMEM_MAD56
SAS_XMEM_MAD66
SAS_XMEM_MAD76
SAS_XMEM_MAD86
SAS_XMEM_MAD96
SAS_XMEM_MAD106
SAS_XMEM_MAD116
SAS_XMEM_MAD126
SAS_XMEM_MAD136
SAS_XMEM_MAD146
SAS_XMEM_MAD156
SAS_XMEM_MAD166
SAS_XMEM_MAD176
SAS_XMEM_MAD186
SAS_XMEM_MAD196
SAS_XMEM_MAD206
SAS_XMEM_MAD216
SAS_XMEM_MAD226
RESET IC_RESET# 5,15
Title
Size Document Number Rev
Date: Sheet
of
Honey_Badger_SEB 1
PBSRAM&FLASH
A3
9 22Tuesday, April 07, 2015
Wiwynn
H/W R&D Dept. II
8F,90,Sec. 1,Hsin Tai Wu Rd,
Hsichih, Taipei Hsien 221, Taiwan, R.O.C
Title
Size Document Number Rev
Date: Sheet
of
Honey_Badger_SEB 1
PBSRAM&FLASH
A3
9 22Tuesday, April 07, 2015
Wiwynn
H/W R&D Dept. II
8F,90,Sec. 1,Hsin Tai Wu Rd,
Hsichih, Taipei Hsien 221, Taiwan, R.O.C
Title
Size Document Number Rev
Date: Sheet
of
Honey_Badger_SEB 1
PBSRAM&FLASH
A3
9 22Tuesday, April 07, 2015
Wiwynn
H/W R&D Dept. II
8F,90,Sec. 1,Hsin Tai Wu Rd,
Hsichih, Taipei Hsien 221, Taiwan, R.O.C
R100
4K75R2F-1-GP
DYR100
4K75R2F-1-GP
DY
1 2
C161 
SC1U10V2KX-4-GP 
C161 
SC1U10V2KX-4-GP 
1 2
C173 
SCD1U16V2KX-3GP 
DY
C173 
SCD1U16V2KX-3GP 
DY 1 2
TP129 TPAD32-GPTP129 TPAD32-GP1
C176 
SCD1U16V2KX-3GP 
DY
C176 
SCD1U16V2KX-3GP 
DY 1 2
R98
0R2J-2-GP
DY
R98
0R2J-2-GP
DY
1 2
C167 
SCD1U16V2KX-3GP 
DY
C167 
SCD1U16V2KX-3GP 
DY 1 2
C170 
SCD1U16V2KX-3GP 
DY
C170 
SCD1U16V2KX-3GP 
DY 1 2
R96 
4K75R2F-1-GP 
DY
R96 
4K75R2F-1-GP 
DY
1 2
R104
4K75R2F-1-GP
DYR104
4K75R2F-1-GP
DY
1 2
TP130 TPAD32-GPTP130 TPAD32-GP1
TP132 TPAD32-GPTP132 TPAD32-GP1
C165 
SC22U6D3V5MX-2GP 
DY
C165 
SC22U6D3V5MX-2GP 
DY 1 2
C171 
SCD1U16V2KX-3GP 
DY
C171 
SCD1U16V2KX-3GP 
DY 1 2
C174 
SCD1U16V2KX-3GP 
DY
C174 
SCD1U16V2KX-3GP 
DY 1 2
R106 
220R2F-GP 
R106 
220R2F-GP 
1 2
C160 
SC1U10V2KX-4-GP 
C160 
SC1U10V2KX-4-GP 
1 2
C177 
SCD1U16V2KX-3GP 
DY
C177 
SCD1U16V2KX-3GP 
DY 1 2
TP133 TPAD32-GPTP133 TPAD32-GP1
C168 
SCD1U16V2KX-3GP 
DY
C168 
SCD1U16V2KX-3GP 
DY 1 2
C164 
SC22U6D3V5MX-2GP 
DY
C164 
SC22U6D3V5MX-2GP 
DY 1 2
R101
4K75R2F-1-GP
DY R101
4K75R2F-1-GP
DY1 2R97 
4K75R2F-1-GP 
DY
R97 
4K75R2F-1-GP 
DY
1 2
R99
4K75R2F-1-GP
DY
R99
4K75R2F-1-GP
DY
1 2
R94 
220R2F-GP 
DY
R94 
220R2F-GP 
DY
1 2
R102 
220R2F-GP 
DY
R102 
220R2F-GP 
DY
1 2
U3
S29GL064N90TFI030-GP
U3
S29GL064N90TFI030-GP
WE#11
RESET# 12
WP#/ACC 14
CE#26 VSS 27
OE#28
VCC37
VSS 46
BYTE# 47
A151 A142 A133 A124 A115 A106 A97 A88
A199
A2010
A2113
RY/BY# 15A1816 A1717
A718 A619 A520 A421 A322 A223 A124 A025
A1648
DQ0 29
DQ8 30
DQ1 31
DQ9 32
DQ2 33
DQ10 34
DQ3 35
DQ11 36
DQ4 38
DQ12 39
DQ5 40
DQ13 41
DQ6 42
DQ14 43
DQ7 44
DQ15/A-1 45
R103 
4K75R2F-1-GP 
R103 
4K75R2F-1-GP 
1 2
U2
CY7C1440AV33-250AXC-GP
DYU2
CY7C1440AV33-250AXC-GP
DY
CLK89
ZZ64
CS2#92
CS297
CS1#98
BW#87
GWE#88
BWED#96
BWEC#95
BWEB#94
BWEA#93
ADSP#84
ADSC#85
OE#86
LBO#31
ADV#83
A1939
A1842
A1743
A1650
A1549
A1448
A1347
A1246
A1145
A1044
A981
A882
A799
A6100
A532
A433
A334
A235
A136
A037
VDD91
VDD65
VDD41
VDD15
GND90
GND67
GND40
GND17
NC#6666
NC#3838
NC#1616
NC#1414
DQD_PAR 30
DQC_PAR 1
DQB_PAR 80
DQA_PAR 51
DQD0 18DQD1 19DQD2 22DQD3 23DQD4 24DQD5 25DQD6 28DQD7 29
DQC0 2DQC1 3DQC2 6DQC3 7DQC4 8DQC5 9DQC6 12DQC7 13
DQA0 52DQA1 53DQA2 56DQA3 57DQA4 58DQA5 59DQA6 62DQA7 63
DQB0 68DQB1 69DQB2 72DQB3 73DQB4 74DQB5 75DQB6 78DQB7 79
VDDQ 77
VDDQ 70
VDDQ 61
VDDQ 54
VDDQ 27
VDDQ 20
VDDQ 11
VDDQ 4
VSSQ 76
VSSQ 71
VSSQ 60
VSSQ 55
VSSQ 26
VSSQ 21
VSSQ 10
VSSQ 5
C172 
SCD1U16V2KX-3GP 
DY
C172 
SCD1U16V2KX-3GP 
DY 1 2
C175 
SCD1U16V2KX-3GP 
DY
C175 
SCD1U16V2KX-3GP 
DY 1 2
C166 
SCD1U16V2KX-3GP 
DY
C166 
SCD1U16V2KX-3GP 
DY 1 2
R93 
4K75R2F-1-GP 
DY R93 
4K75R2F-1-GP 
DY 
1 2
TP131 TPAD32-GPTP131 TPAD32-GP1
R105
4K75R2F-1-GP
DYR105
4K75R2F-1-GP
DY
1 2
C163 
SCD1U16V2KX-3GP 
C163 
SCD1U16V2KX-3GP 
1 2
C169 
SCD1U16V2KX-3GP 
DY
C169 
SCD1U16V2KX-3GP 
DY 1 2
R95
0R2J-2-GP
DY
R95
0R2J-2-GP
DY
1 2
TP127 TPAD32-GPTP127 TPAD32-GP1
TP126 TPAD32-GPTP126 TPAD32-GP1
TP128 TPAD32-GPTP128 TPAD32-GP1
C162 
SC1U10V2KX-4-GP 
C162 
SC1U10V2KX-4-GP 
1 2



5
5
4
4
3
3
2
2
1
1
D D
C C
B B
A A
EXT miniSAS CONN
INT miniSAS CONN_A
INT miniSAS CONN_B
CAGE
SAS_EXT_CONN_TX16_P
SAS_EXT_CONN_TX16_N
SAS_EXT_CONN_TX17_P
SAS_EXT_CONN_TX17_N
SAS_EXT_CONN_TX18_P
SAS_EXT_CONN_TX18_N
SAS_EXT_CONN_TX19_P
SAS_EXT_CONN_TX19_N
SAS_EXT_CONN_RX16_P
SAS_EXT_CONN_RX16_N
SAS_EXT_CONN_RX19_N
SAS_EXT_CONN_RX17_P
SAS_EXT_CONN_RX17_N
SAS_EXT_CONN_RX18_N
SAS_EXT_CONN_RX19_P
SAS_EXT_CONN_RX18_P
SAS_INTA_CONN_RX20_N
SAS_INTA_CONN_RX20_P
SAS_INTA_CONN_RX21_N
SAS_INTA_CONN_RX21_P
SAS_INTA_CONN_RX22_P
SAS_INTA_CONN_RX22_N
SAS_INTA_CONN_RX23_P
SAS_INTA_CONN_RX23_N INT_CONN_A_SB3
INT_CONN_A_SB2
INT_CONN_A_SB0
INT_CONN_A_SB1
INT_CONN_A_SB4
INT_CONN_A_SB5
INT_CONN_A_SB6
SAS_INTA_CONN_TX21_N
SAS_INTA_CONN_TX21_P
SAS_INTA_CONN_TX22_N
SAS_INTA_CONN_TX22_P
SAS_INTA_CONN_TX23_N
SAS_INTA_CONN_TX23_P
SAS_INTA_CONN_TX20_N
SAS_INTA_CONN_TX20_P
INT_CONN_A_SB7
SAS_INTB_CONN_RX24_N
SAS_INTB_CONN_RX24_P
SAS_INTB_CONN_RX25_N
SAS_INTB_CONN_RX25_P
SAS_INTB_CONN_RX26_N
SAS_INTB_CONN_RX26_P
SAS_INTB_CONN_RX27_N
SAS_INTB_CONN_RX27_P
SAS_INTB_CONN_TX24_P
SAS_INTB_CONN_TX24_N
SAS_INTB_CONN_TX25_P
SAS_INTB_CONN_TX25_N
SAS_INTB_CONN_TX26_P
SAS_INTB_CONN_TX26_N
SAS_INTB_CONN_TX27_P
SAS_INTB_CONN_TX27_N
INT_CONN_B_SB7
INT_CONN_B_SB3
INT_CONN_B_SB2
INT_CONN_B_SB0
INT_CONN_B_SB1
INT_CONN_B_SB4
INT_CONN_B_SB5
INT_CONN_B_SB6
SAS_EXT_RX16_P4
SAS_EXT_RX16_N4
SAS_EXT_RX17_N4
SAS_EXT_RX18_P4
SAS_EXT_RX18_N4
SAS_EXT_RX17_P4
SAS_EXT_RX19_P4
SAS_EXT_RX19_N4
SAS_EXT_CONN_TX16_P 4
SAS_EXT_CONN_TX16_N 4
SAS_EXT_CONN_TX17_P 4
SAS_EXT_CONN_TX17_N 4
SAS_EXT_CONN_TX18_P 4
SAS_EXT_CONN_TX18_N 4
SAS_EXT_CONN_TX19_N 4
SAS_EXT_CONN_TX19_P 4
SAS_INTA_RX20_N4
SAS_INTA_RX20_P4
SAS_INTB_RX24_N4
SAS_INTB_RX24_P4
SAS_INTA_RX21_P4
SAS_INTA_RX21_N4
SAS_INTA_RX22_N4
SAS_INTA_RX22_P4
SAS_INTA_RX23_N4
SAS_INTA_RX23_P4
SAS_INTA_CONN_TX21_P4
SAS_INTA_CONN_TX21_N4
SAS_INTA_CONN_TX22_N4
SAS_INTA_CONN_TX22_P4
SAS_INTA_CONN_TX23_N4
SAS_INTA_CONN_TX23_P4
SAS_INTA_CONN_TX20_P4
SAS_INTA_CONN_TX20_N4
SAS_INTB_RX25_P4
SAS_INTB_RX25_N4
SAS_INTB_RX26_N4
SAS_INTB_RX26_P4
SAS_INTB_RX27_N4
SAS_INTB_RX27_P4
SAS_INTB_CONN_TX24_P4
SAS_INTB_CONN_TX24_N4
SAS_INTB_CONN_TX25_P4
SAS_INTB_CONN_TX25_N4
SAS_INTB_CONN_TX26_N4
SAS_INTB_CONN_TX26_P4
SAS_INTB_CONN_TX27_N4
SAS_INTB_CONN_TX27_P4
Title
Size Document Number Rev
Date: Sheet
of
Honey_Badger_SEB 1
INT&EXT SAS CONNs
A3
10 22Tuesday, April 07, 2015
Wiwynn
H/W R&D Dept. II
8F,90,Sec. 1,Hsin Tai Wu Rd,
Hsichih, Taipei Hsien 221, Taiwan, R.O.C
Title
Size Document Number Rev
Date: Sheet
of
Honey_Badger_SEB 1
INT&EXT SAS CONNs
A3
10 22Tuesday, April 07, 2015
Wiwynn
H/W R&D Dept. II
8F,90,Sec. 1,Hsin Tai Wu Rd,
Hsichih, Taipei Hsien 221, Taiwan, R.O.C
Title
Size Document Number Rev
Date: Sheet
of
Honey_Badger_SEB 1
INT&EXT SAS CONNs
A3
10 22Tuesday, April 07, 2015
Wiwynn
H/W R&D Dept. II
8F,90,Sec. 1,Hsin Tai Wu Rd,
Hsichih, Taipei Hsien 221, Taiwan, R.O.C
TP139 TPAD32-GPTP139 TPAD32-GP1
C182 SCD01U50V2KX-1GPC182 SCD01U50V2KX-1GP1 2
C195 SCD01U50V2KX-1GPC195 SCD01U50V2KX-1GP1 2
C198 SCD01U50V2KX-1GPC198 SCD01U50V2KX-1GP1 2
CN3
AMP-CONN36-2R-GP
CN3
AMP-CONN36-2R-GP
SIGNAL_GROUND A1
RX_0+A2
RX_0-A3
SIGNAL_GROUND A4
RX_1+A5
RX_1-A6
SIGNAL_GROUND A7
SIDEBAND_7 A8
SIDEBAND_3 A9
SIDEBAND_4 A10
SIDEBAND_5 A11
SIGNAL_GROUND A12
RX_2+A13
RX_2-A14
SIGNAL_GROUND A15
RX_3+A16
RX_3-A17
SIGNAL_GROUND A18
SIGNAL_GROUND B1
TX_0+B2
TX_0-B3
SIGNAL_GROUND B4
TX_1+B5
TX_1-B6
SIGNAL_GROUND B7
SIDEBAND_0 B8
SIDEBAND_1 B9
SIDEBAND_2 B10
SIDEBAND_6 B11
SIGNAL_GROUND B12
TX_2+B13
TX_2-B14
SIGNAL_GROUND B15
TX_3+B16
TX_3-B17
SIGNAL_GROUND B18NP1NP1
NP2NP2
37 37
38 38
39 39
40 40
41 41
42 42
C190 SCD01U50V2KX-1GPC190 SCD01U50V2KX-1GP1 2
C179 SCD01U50V2KX-1GPC179 SCD01U50V2KX-1GP1 2
C192 SCD01U50V2KX-1GPC192 SCD01U50V2KX-1GP1 2
TP140 TPAD32-GPTP140 TPAD32-GP1
C186 SCD01U50V2KX-1GPC186 SCD01U50V2KX-1GP1 2
TP157 TPAD32-GPTP157 TPAD32-GP1
CN7
MLX-CON7-16-GP
CN7
MLX-CON7-16-GP
NP1
NP2
Z5
Z6
Z7
Z1
Z2
Z3Z4
TP159 TPAD32-GPTP159 TPAD32-GP1
C184 SCD01U50V2KX-1GPC184 SCD01U50V2KX-1GP1 2
CN1
MLX-CONN26-GP
CN1
MLX-CONN26-GP
RX_0+A2
RX_0-A3
RX_1+A5
RX_1-A6
RX_2+A8
RX_2-A9
RX_3+A11
RX_3-A12
TX_0+ B2
TX_0- B3
TX_1+ B5
TX_1- B6
TX_2+ B8
TX_2- B9
TX_3+ B11
TX_3- B12
SIGNAL_GROUND A1
SIGNAL_GROUND A4
SIGNAL_GROUND A7
SIGNAL_GROUND A10
SIGNAL_GROUND A13
SIGNAL_GROUND B1
SIGNAL_GROUND B4
SIGNAL_GROUND B7
SIGNAL_GROUND B10
SIGNAL_GROUND B13
NP1NP1 NP2NP2
TP135 TPAD32-GPTP135 TPAD32-GP1
C201 SCD01U50V2KX-1GPC201 SCD01U50V2KX-1GP1 2
C196 SCD01U50V2KX-1GPC196 SCD01U50V2KX-1GP1 2
C197 SCD01U50V2KX-1GPC197 SCD01U50V2KX-1GP1 2
TP141 TPAD32-GPTP141 TPAD32-GP1
C194 SCD01U50V2KX-1GPC194 SCD01U50V2KX-1GP1 2
TP136 TPAD32-GPTP136 TPAD32-GP1
C188 SCD01U50V2KX-1GPC188 SCD01U50V2KX-1GP1 2
TP161 TPAD32-GPTP161 TPAD32-GP1
TP155 TPAD32-GPTP155 TPAD32-GP1
C199 SCD01U50V2KX-1GPC199 SCD01U50V2KX-1GP1 2
C181 SCD01U50V2KX-1GPC181 SCD01U50V2KX-1GP1 2
TP137 TPAD32-GPTP137 TPAD32-GP1
TP134 TPAD32-GPTP134 TPAD32-GP1
C183 SCD01U50V2KX-1GPC183 SCD01U50V2KX-1GP1 2
TP160 TPAD32-GPTP160 TPAD32-GP1
C193 SCD01U50V2KX-1GPC193 SCD01U50V2KX-1GP1 2
TP154 TPAD32-GPTP154 TPAD32-GP1
C178 SCD01U50V2KX-1GPC178 SCD01U50V2KX-1GP1 2
C191 SCD01U50V2KX-1GPC191 SCD01U50V2KX-1GP1 2
TP138 TPAD32-GPTP138 TPAD32-GP1
TP158 TPAD32-GPTP158 TPAD32-GP1
C187 SCD01U50V2KX-1GPC187 SCD01U50V2KX-1GP1 2
C189 SCD01U50V2KX-1GPC189 SCD01U50V2KX-1GP1 2
C200 SCD01U50V2KX-1GPC200 SCD01U50V2KX-1GP1 2
C180 SCD01U50V2KX-1GPC180 SCD01U50V2KX-1GP1 2
CN2
AMP-CONN36-2R-GP
CN2
AMP-CONN36-2R-GP
SIGNAL_GROUND A1
RX_0+A2
RX_0-A3
SIGNAL_GROUND A4
RX_1+A5
RX_1-A6
SIGNAL_GROUND A7
SIDEBAND_7 A8
SIDEBAND_3 A9
SIDEBAND_4 A10
SIDEBAND_5 A11
SIGNAL_GROUND A12
RX_2+A13
RX_2-A14
SIGNAL_GROUND A15
RX_3+A16
RX_3-A17
SIGNAL_GROUND A18
SIGNAL_GROUND B1
TX_0+B2
TX_0-B3
SIGNAL_GROUND B4
TX_1+B5
TX_1-B6
SIGNAL_GROUND B7
SIDEBAND_0 B8
SIDEBAND_1 B9
SIDEBAND_2 B10
SIDEBAND_6 B11
SIGNAL_GROUND B12
TX_2+B13
TX_2-B14
SIGNAL_GROUND B15
TX_3+B16
TX_3-B17
SIGNAL_GROUND B18NP1NP1
NP2NP2
37 37
38 38
39 39
40 40
41 41
42 42
TP156 TPAD32-GPTP156 TPAD32-GP1
C185 SCD01U50V2KX-1GPC185 SCD01U50V2KX-1GP1 2



5
5
4
4
3
3
2
2
1
1
D D
C C
B B
A A
Re-Driver IC lane 0 and 1
Re-Driver IC lane 0 and 1
x16 PCIe 164 PINs GOLDEN FINGER
         STRADDLE TYPE x1 PCIe 36 PINs GOLDEN FINGER
         STRADDLE TYPE
SAS_HDD_RX0_P
SAS_HDD_RX0_N
SAS_HDD_RX1_P
SAS_HDD_RX1_N
SAS_HDD_RX2_P
SAS_HDD_RX2_N
SAS_HDD_RX3_P
SAS_HDD_RX3_N
SAS_HDD_RX4_P
SAS_HDD_RX4_N
SAS_HDD_RX5_P
SAS_HDD_RX5_N
SAS_HDD_RX6_P
SAS_HDD_RX6_N
SAS_HDD_CONN_RX7_P
SAS_HDD_CONN_RX7_N
SAS_HDD_CONN_RX8_P
SAS_HDD_CONN_RX8_N
SAS_HDD_RX9_P
SAS_HDD_RX9_N
SAS_HDD_PRE15
SAS_HDD_CONN_TX0_P
SAS_HDD_CONN_TX0_N
SAS_HDD_CONN_TX1_P
SAS_HDD_CONN_TX1_N
SAS_HDD_CONN_TX2_P
SAS_HDD_CONN_TX2_N
SAS_HDD_CONN_TX3_P
SAS_HDD_CONN_TX3_N
SAS_HDD_CONN_TX4_P
SAS_HDD_CONN_TX4_N
SAS_HDD_CONN_TX5_P
SAS_HDD_CONN_TX5_N
SAS_HDD_CONN_TX6_P
SAS_HDD_CONN_TX6_N
SAS_HDD_CONN_TX7_P
SAS_HDD_CONN_TX7_N
SAS_HDD_CONN_TX8_P
SAS_HDD_CONN_TX8_N
SAS_HDD_CONN_TX9_P
SAS_HDD_CONN_TX9_N
SAS_Fault_LED1
SAS_Fault_LED0
SAS_Fault_LED2
SAS_Fault_LED3
SAS_Fault_LED4
SAS_Fault_LED5
SAS_Fault_LED6
SAS_Fault_LED13
SAS_Fault_LED12
SAS_Fault_LED11
SAS_Fault_LED10
SAS_Fault_LED7
SAS_Fault_LED8
SAS_I2C_C_BUF_SDA_R
SAS_I2C_C_BUF_SCL_R
SAS_I2C_D_BUF_SDA_R
SAS_I2C_D_BUF_SCL_R
HB_OUT
HB_INPUT
SAS_Fault_LED15
SAS_Fault_LED14
SAS_Fault_LED9
SELF_TRAY
PCIe_MATED
ID&I2C_ADD
PEER_TRAY
FAN_PWM_PCIe
SAS_SEB_PEER_PRSNT
SAS_HDD_CONN_TX10_P
SAS_HDD_CONN_TX10_N
SAS_HDD_CONN_TX11_P
SAS_HDD_CONN_TX11_N
SAS_HDD_CONN_TX12_P
SAS_HDD_CONN_TX12_N
SAS_HDD_CONN_TX13_P
SAS_HDD_CONN_TX13_N
SAS_HDD_CONN_TX14_P
SAS_HDD_CONN_TX14_N
SAS_HDD_CONN_TX15_P
SAS_HDD_CONN_TX15_N
SAS_HDD_RX10_P
SAS_HDD_RX10_N
SAS_HDD_RX11_P
SAS_HDD_RX11_N
SAS_HDD_RX12_P
SAS_HDD_RX12_N
SAS_HDD_RX13_N
SAS_HDD_RX13_P
SAS_HDD_RX14_P
SAS_HDD_RX14_N
SAS_HDD_RX15_P
SAS_HDD_RX15_N
SHUTDOWN_RELEASE
PEER_1A_2A_HB
FCB_HW_REVISION
DPB_HW_REVISION
TRAY_ID
PEER_1B_2B_HB
SAS_I2C_B_BUF_SCL_R
SAS_I2C_B_BUF_SDA_R
SAS_I2C_B_BUF_SDA_R
SAS_I2C_B_BUF_SCL_R
SAS_I2C_C_BUF_SCL_R
SAS_I2C_C_BUF_SDA_R
SAS_I2C_D_BUF_SCL_R
SAS_I2C_D_BUF_SDA_R
12V_PCIe
12V_PCIe
3D3V
SAS_HDD_RX0_N3
SAS_HDD_RX0_P3
SAS_HDD_RX1_N3
SAS_HDD_RX1_P3
SAS_HDD_RX2_N3
SAS_HDD_RX2_P3
SAS_HDD_RX3_N3
SAS_HDD_RX3_P3
SAS_HDD_RX4_N3
SAS_HDD_RX4_P3
SAS_HDD_RX5_N3
SAS_HDD_RX5_P3
SAS_HDD_RX6_N3
SAS_HDD_RX6_P3
SAS_HDD_CONN_RX7_N13
SAS_HDD_CONN_RX7_P13
SAS_HDD_CONN_RX8_N13
SAS_HDD_CONN_RX8_P13
SAS_HDD_RX9_N3
SAS_HDD_RX9_P3
SAS_HDD_CONN_TX0_P 3
SAS_HDD_CONN_TX0_N 3
SAS_HDD_CONN_TX1_P 3
SAS_HDD_CONN_TX1_N 3
SAS_HDD_CONN_TX2_P 3
SAS_HDD_CONN_TX2_N 3
SAS_HDD_CONN_TX3_P 3
SAS_HDD_CONN_TX3_N 3
SAS_HDD_CONN_TX4_P 3
SAS_HDD_CONN_TX4_N 3
SAS_HDD_CONN_TX5_P 3
SAS_HDD_CONN_TX5_N 3
SAS_HDD_CONN_TX6_P 3
SAS_HDD_CONN_TX6_N 3
SAS_HDD_CONN_TX7_P 13
SAS_HDD_CONN_TX7_N 13
SAS_HDD_CONN_TX8_P 13
SAS_HDD_CONN_TX8_N 13
SAS_HDD_CONN_TX9_P 3
SAS_HDD_CONN_TX9_N 3
SAS_Fault_LED15
SAS_Fault_LED05
SAS_Fault_LED25
SAS_Fault_LED35
SAS_Fault_LED45
SAS_Fault_LED55
SAS_Fault_LED65
SAS_Fault_LED13 5
SAS_Fault_LED10 5
SAS_Fault_LED11 5
SAS_Fault_LED12 5
SAS_HDD_PRE15 5
SAS_Fault_LED75
SAS_Fault_LED85
Temp_1_A0 14
Temp_2_A0 14
SAS_GPIO0 5
HB_OUT 16
SAS_GPIO4 5
SAS_Fault_LED15 5
SAS_Fault_LED14 5
SAS_Fault_LED9 5
SAS_HDD_PWR1_PCIe 12
SAS_HDD_PWR2_PCIe 12
SAS_HDD_PWR3_PCIe 12
SAS_HDD_PWR4_PCIe 12
SAS_HDD_PWR5_PCIe 12
SAS_HDD_PWR6_PCIe 12
SAS_HDD_PWR7_PCIe 12
SAS_HDD_PWR8_PCIe 12
SAS_HDD_PWR9_PCIe 12
SAS_HDD_PWR0_PCIe 12
SAS_HDD_PWR10_PCIe 12
SAS_HDD_PRE95
SAS_HDD_PRE85
SAS_HDD_PRE75
SAS_HDD_PRE65
SAS_HDD_PRE55
SAS_HDD_PRE45
SAS_HDD_PRE35
SAS_HDD_PRE25
SAS_HDD_PRE15
SAS_HDD_PRE05
SAS_HDD_PRE145
SAS_HDD_PRE135
SAS_HDD_PRE125
SAS_HDD_PRE115
SAS_HDD_PRE105
SAS_HDD_PWR15_PCIe 12
SAS_HDD_PWR11_PCIe 12
SAS_HDD_PWR12_PCIe 12
SAS_HDD_PWR13_PCIe 12
SAS_HDD_PWR14_PCIe 12
SAS_GPIO55
SAS_GPIO65
FAN_PWM_PCIe 12
PCIe_MATED# 12,19
SAS_HDD_CONN_TX10_P 3
SAS_HDD_CONN_TX10_N 3
SAS_HDD_CONN_TX11_P 3
SAS_HDD_CONN_TX11_N 3
SAS_HDD_CONN_TX12_P 3
SAS_HDD_CONN_TX12_N 3
SAS_HDD_CONN_TX13_P 3
SAS_HDD_CONN_TX13_N 3
SAS_HDD_CONN_TX14_P 3
SAS_HDD_CONN_TX14_N 3
SAS_HDD_CONN_TX15_P 3
SAS_HDD_CONN_TX15_N 3
SAS_HDD_RX10_N3
SAS_HDD_RX10_P3
SAS_HDD_RX11_N3
SAS_HDD_RX11_P3
SAS_HDD_RX12_N3
SAS_HDD_RX12_P3
SAS_HDD_RX13_N3
SAS_HDD_RX13_P3
SAS_HDD_RX14_N3
SAS_HDD_RX14_P3
SAS_HDD_RX15_P3
SAS_HDD_RX15_N3
SHUTDOWN_RELEASE16
FCB_HW_REVISION 5
DPB_HW_REVISION 5
SAS_GPIO15
PEER_1B_2B_HB5
PEER_1A_2A_HB 5
SAS_I2C_B_BUF_SDA 14
SAS_I2C_B_BUF_SCL 14
SAS_I2C_C_BUF_SCL 14
SAS_I2C_C_BUF_SDA 14
SAS_I2C_D_BUF_SDA 14
SAS_I2C_D_BUF_SCL 14
SAS_GPIO105
EXP_TEMP_A1 14
Title
Size Document Number Rev
Date: Sheet
of
Honey_Badger_SEB 1
PCIe GOLD FINGER
A3
11 22Tuesday, April 07, 2015
Wiwynn
H/W R&D Dept. II
8F,90,Sec. 1,Hsin Tai Wu Rd,
Hsichih, Taipei Hsien 221, Taiwan, R.O.C
Title
Size Document Number Rev
Date: Sheet
of
Honey_Badger_SEB 1
PCIe GOLD FINGER
A3
11 22Tuesday, April 07, 2015
Wiwynn
H/W R&D Dept. II
8F,90,Sec. 1,Hsin Tai Wu Rd,
Hsichih, Taipei Hsien 221, Taiwan, R.O.C
Title
Size Document Number Rev
Date: Sheet
of
Honey_Badger_SEB 1
PCIe GOLD FINGER
A3
11 22Tuesday, April 07, 2015
Wiwynn
H/W R&D Dept. II
8F,90,Sec. 1,Hsin Tai Wu Rd,
Hsichih, Taipei Hsien 221, Taiwan, R.O.C
R354 0R2J-2-GPR354 0R2J-2-GP1 2
TOPBOTTOM
GF1
GF-X16-U
TOPBOTTOM
GF1
GF-X16-U
B1 B1
B2 B2
B3 B3
B4 B4
B5 B5
B6 B6
B7 B7
B8 B8
B9 B9
B10 B10
B11 B11
B12 B12
B13 B13
B14 B14
B15 B15
B16 B16
B17 B17
B18 B18
B19 B19
B20 B20
B21 B21
B22 B22
B23 B23
B24 B24
B25 B25
B26 B26
B27 B27
B28 B28
B29 B29
B30 B30
B31 B31
B32 B32
B33 B33
B34 B34
B35 B35
B36 B36
B37 B37
B38 B38
B39 B39
B40 B40
B41 B41
B42 B42
B43 B43
B44 B44
B45 B45
B46 B46
B47 B47
B48 B48
B49 B49
B50 B50
B51 B51
B52 B52
B53 B53
B54 B54
B55 B55
B56 B56
B57 B57
B58 B58
B59 B59
B60 B60
B61 B61
B62 B62
B63 B63
B64 B64
B65 B65
B66 B66
B67 B67
B68 B68
B69 B69
B70 B70
B71 B71
B72 B72
B73 B73
B74 B74
B75 B75
B76 B76
B77 B77
B78 B78
B79 B79
B80 B80
B81 B81
B82 B82
A1A1
A2A2
A3A3
A4A4
A5A5
A6A6
A7A7
A8A8
A9A9
A10A10
A11A11
A12A12
A13A13
A14A14
A15A15
A16A16
A17A17
A18A18
A19A19
A20A20
A21A21
A22A22
A23A23
A24A24
A25A25
A26A26
A27A27
A28A28
A29A29
A30A30
A31A31
A32A32
A33A33
A34A34
A35A35
A36A36
A37A37
A38A38
A39A39
A40A40
A41A41
A42A42
A43A43
A44A44
A45A45
A46A46
A47A47
A48A48
A49A49
A50A50
A51A51
A52A52
A53A53
A54A54
A55A55
A56A56
A57A57
A58A58
A59A59
A60A60
A61A61
A62A62
A63A63
A64A64
A65A65
A66A66
A67A67
A68A68
A69A69
A70A70
A71A71
A72A72
A73A73
A74A74
A75A75
A76A76
A77A77
A78A78
A79A79
A80A80
A81A81
A82A82
R110 0R2J-2-GPR110 0R2J-2-GP1 2
R107 0R2J-2-GPR107 0R2J-2-GP1 2
R351 0R2J-2-GPR351 0R2J-2-GP1 2
R113
0R2J-2-GP
R113
0R2J-2-GP
1 2
R261 0R2J-2-GPR261 0R2J-2-GP1 2
R356 0R2J-2-GPR356 0R2J-2-GP1 2
R352 0R2J-2-GPR352 0R2J-2-GP1 2
R1080R2J-2-GP R1080R2J-2-GP 12
R353 0R2J-2-GPR353 0R2J-2-GP1 2
R299
10KR2F-2-GP
R299
10KR2F-2-GP
1 2
R297 0R2J-2-GPR297 0R2J-2-GP1 2
R111
0R2J-2-GP
R111
0R2J-2-GP
1 2
R298
27KR2F-L-GP
R298
27KR2F-L-GP
1 2
TopBottom
02 Do not mirror 
GF2
GF-PCIE-36P-GP
TopBottom
02 Do not mirror 
GF2
GF-PCIE-36P-GP
B1 B1
B2 B2
B3 B3
B4 B4
B5 B5
B6 B6
B7 B7
B8 B8
B9 B9
B10 B10
B11 B11
B12 B12
B13 B13
B14 B14
B15 B15
B16 B16
B17 B17
B18 B18
A1A1
A2A2
A3A3
A4A4
A5A5
A6A6
A7A7
A8A8
A9A9
A10A10
A11A11
A12A12
A13A13
A14A14
A15A15
A16A16
A17A17
A18A18
R355 0R2J-2-GPR355 0R2J-2-GP1 2
R259 0R2J-2-GPR259 0R2J-2-GP1 2
R109
0R2J-2-GP
R109
0R2J-2-GP
1 2
R300
10KR2F-2-GP
R300
10KR2F-2-GP
1 2



5
5
4
4
3
3
2
2
1
1
D D
C C
B B
A A
RESERVE FOR BYPASS 
BUS SWITCH
FAN_PWM
SAS_HDD_PWR10_PCIe
SAS_HDD_PWR11_PCIe
SAS_HDD_PWR12_PCIe
SAS_HDD_PWR13_PCIe
SAS_HDD_PWR14_PCIe
SAS_HDD_PWR15_PCIe
FAN_PWM_PCIe
PCIe_MATED#_A
FAN_PWM
PCIe_MATED#_B
SAS_HDD_PWR7_PCIe
SAS_HDD_PWR8_PCIe
SAS_HDD_PWR9_PCIe
SAS_HDD_PWR5_PCIe
SAS_HDD_PWR6_PCIe
SAS_HDD_PWR1_PCIe
SAS_HDD_PWR2_PCIe
SAS_HDD_PWR3_PCIe
SAS_HDD_PWR4_PCIe
SAS_HDD_PWR0_PCIe
3D3V
3D3V
SAS_HDD_PWR9 5
SAS_HDD_PWR6 5
SAS_HDD_PWR7 5
SAS_HDD_PWR8 5
SAS_HDD_PWR5 5
SAS_HDD_PWR4 5
SAS_HDD_PWR3 5
SAS_HDD_PWR2 5
SAS_HDD_PWR1 5
SAS_HDD_PWR0 5
SAS_HDD_PWR15 5
SAS_HDD_PWR14 5
SAS_HDD_PWR13 5
SAS_HDD_PWR12 5
SAS_HDD_PWR11 5
SAS_HDD_PWR10 5
SAS_HDD_PWR7_PCIe11
SAS_HDD_PWR8_PCIe11
SAS_HDD_PWR9_PCIe11
SAS_HDD_PWR5_PCIe11
SAS_HDD_PWR6_PCIe11
SAS_HDD_PWR1_PCIe11
SAS_HDD_PWR2_PCIe11
SAS_HDD_PWR3_PCIe11
SAS_HDD_PWR4_PCIe11
SAS_HDD_PWR0_PCIe11
SAS_HDD_PWR10_PCIe11
SAS_HDD_PWR11_PCIe11
SAS_HDD_PWR12_PCIe11
SAS_HDD_PWR13_PCIe11
SAS_HDD_PWR14_PCIe11
SAS_HDD_PWR15_PCIe11
FAN_PWM_PCIe11
PCIe_MATED# 11,19
PCIe_MATED# 11,19
SAS_HDD_PWR9 5
SAS_HDD_PWR6 5
SAS_HDD_PWR7 5
SAS_HDD_PWR8 5
SAS_HDD_PWR5 5
SAS_HDD_PWR4 5
SAS_HDD_PWR3 5
SAS_HDD_PWR2 5
SAS_HDD_PWR1 5
SAS_HDD_PWR0 5
SAS_HDD_PWR10_PCIe11
SAS_HDD_PWR11_PCIe11
SAS_HDD_PWR12_PCIe11
SAS_HDD_PWR13_PCIe11
SAS_HDD_PWR14_PCIe11
SAS_HDD_PWR15_PCIe11
FAN_PWM_PCIe11
SAS_HDD_PWR15 5
SAS_GPIO3 5
SAS_HDD_PWR14 5
SAS_HDD_PWR13 5
SAS_HDD_PWR12 5
SAS_HDD_PWR11 5
SAS_HDD_PWR10 5
SAS_HDD_PWR7_PCIe11
SAS_HDD_PWR8_PCIe11
SAS_HDD_PWR9_PCIe11
SAS_HDD_PWR5_PCIe11
SAS_HDD_PWR6_PCIe11
SAS_HDD_PWR1_PCIe11
SAS_HDD_PWR2_PCIe11
SAS_HDD_PWR3_PCIe11
SAS_HDD_PWR4_PCIe11
SAS_HDD_PWR0_PCIe11
Title
Size Document Number Rev
Date: Sheet
of
Honey_Badger_SEB 1
BUS SWITCH
A3
12 22Tuesday, April 07, 2015
Wiwynn
H/W R&D Dept. II
8F,90,Sec. 1,Hsin Tai Wu Rd,
Hsichih, Taipei Hsien 221, Taiwan, R.O.C
Title
Size Document Number Rev
Date: Sheet
of
Honey_Badger_SEB 1
BUS SWITCH
A3
12 22Tuesday, April 07, 2015
Wiwynn
H/W R&D Dept. II
8F,90,Sec. 1,Hsin Tai Wu Rd,
Hsichih, Taipei Hsien 221, Taiwan, R.O.C
Title
Size Document Number Rev
Date: Sheet
of
Honey_Badger_SEB 1
BUS SWITCH
A3
12 22Tuesday, April 07, 2015
Wiwynn
H/W R&D Dept. II
8F,90,Sec. 1,Hsin Tai Wu Rd,
Hsichih, Taipei Hsien 221, Taiwan, R.O.C
U18
PI3C3861-AQE-GP
U18
PI3C3861-AQE-GP
NC#11
A02
A13
A24
A35
A46
A57
A68
A79
A810
A911
GND 12
B9 13B8 14B7 15B6 16B5 17B4 18B3 19B2 20B1 21B0 22
BE# 23VCC24
R276 0R2J-2-GPDY R276 0R2J-2-GPDY 1 2
R277 0R2J-2-GPDY R277 0R2J-2-GPDY 1 2
R275 0R2J-2-GPDY R275 0R2J-2-GPDY 1 2
R278 0R2J-2-GPDY R278 0R2J-2-GPDY 1 2
R272 0R2J-2-GPDY R272 0R2J-2-GPDY 1 2
R291
0R2J-2-GP
R291
0R2J-2-GP
1 2
C271
SCD1U16V2KX-3GP
C271
SCD1U16V2KX-3GP
1 2
C269
SCD1U16V2KX-3GP
C269
SCD1U16V2KX-3GP
1 2
R268 0R2J-2-GPDY R268 0R2J-2-GPDY 1 2
R269 0R2J-2-GPDY R269 0R2J-2-GPDY 1 2
R267 0R2J-2-GPDY R267 0R2J-2-GPDY 1 2
R274 0R2J-2-GPDY R274 0R2J-2-GPDY 1 2
R279 0R2J-2-GPDY R279 0R2J-2-GPDY 1 2
R270 0R2J-2-GPDY R270 0R2J-2-GPDY 1 2
R264 0R2J-2-GPDY R264 0R2J-2-GPDY 1 2
U17
PI3C3861-AQE-GP
U17
PI3C3861-AQE-GP
NC#11
A02
A13
A24
A35
A46
A57
A68
A79
A810
A911
GND 12
B9 13B8 14B7 15B6 16B5 17B4 18B3 19B2 20B1 21B0 22
BE# 23VCC24
R266 0R2J-2-GPDY R266 0R2J-2-GPDY 1 2
R137
0R2J-2-GP
R137
0R2J-2-GP
1 2
R292
0R2J-2-GP
R292
0R2J-2-GP
1 2
C270
SC1U10V2KX-1GP
C270
SC1U10V2KX-1GP
1 2
R273 0R2J-2-GPDY R273 0R2J-2-GPDY 1 2
C268
SC1U10V2KX-1GP
C268
SC1U10V2KX-1GP
1 2
R280 0R2J-2-GPDY R280 0R2J-2-GPDY 1 2
R271 0R2J-2-GPDY R271 0R2J-2-GPDY 1 2
R265 0R2J-2-GPDY R265 0R2J-2-GPDY 1 2



5
5
4
4
3
3
2
2
1
1
D D
C C
B B
A A
ADD=1100001 (0xC2)
ADD=1001000 (0x92)
VOLTAGE SENSOR
ADD=1100000 (0xC0)
LED DRIVER
ADD=1010001 (0xA2)
EEPROM
RESERVE FOR BYPASS send from expander
send from HDD
send from expander to HDD
send from HDD to Expander
1.2V_REDV
REDV_I2C_A0
REDV_I2C_A1
REDV_I2C_A4
REDV_D1_A
REDV_D2_A
REDV_D1_B
REDV_D2_B
REDV_I2C_SEL1A
REDV_I2C_SEL2A
REDV_I2C_SEL1B
REDV_I2C_SEL2B
REDV_PD#
REDV_MODE
3D3V_SENSE
1D8V_SENSE
VOL_SEN_ADDR
1D2V_SENSE
VOL_SEN_ALERT
VOL_SEN_SCL
VOL_SEN_SDA
1V_SENSE
LED_DR_RESET#
LED_DR_LED0
LED_DR_LED1
LED_DR_A0
LED_DR_I2C_SCL
LED_DR_I2C_SDA
SEB_EEPROM_A0
SEB_EEPROM_A1 SEB_EEPROM_WP
SEB_EEPROM_SDA
SEB_EEPROM_A2
SEB_EEPROM_SCL
SAS_HDD_REDV_SER_TX7_P
SAS_HDD_REDV_SER_TX7_N
SAS_HDD_REDV_SER_TX8_P
SAS_HDD_REDV_SER_TX8_N
SAS_HDD_CONN_SER_RX7_P
REDV_TX7_P
SAS_HDD_CONN_SER_TX7_P
REDV_TX7_N
SAS_HDD_REDV_SER_TX7_P
SAS_HDD_REDV_SER_TX7_N SAS_HDD_CONN_SER_TX7_N
SAS_HDD_REDV_SER_TX8_P
REDV_TX8_P
SAS_HDD_CONN_SER_TX8_P
REDV_TX8_N
SAS_HDD_CONN_SER_TX8_NSAS_HDD_REDV_SER_TX8_N
SAS_HDD_CONN_SER_RX7_N
REDV_RX7_N
REDV_RX8_P
SAS_HDD_REDV_SER_RX7_N
SAS_HDD_REDV_SER_RX8_P
SAS_HDD_CONN_SER_RX7_P
SAS_HDD_CONN_SER_RX8_P
REDV_RX7_P
REDV_RX8_N
SAS_HDD_REDV_SER_RX8_NSAS_HDD_CONN_SER_RX8_N
SAS_HDD_REDV_SER_RX7_P
SAS_HDD_CONN_SER_RX7_N
SAS_HDD_CONN_SER_RX8_P
SAS_HDD_CONN_SER_RX8_N
SAS_HDD_REDV_SER_RX7_P
SAS_HDD_REDV_SER_RX7_N
SAS_HDD_REDV_SER_RX8_P
SAS_HDD_REDV_SER_RX8_N
SAS_HDD_CONN_SER_TX7_P
SAS_HDD_CONN_SER_TX7_N
SAS_HDD_CONN_SER_TX8_P
SAS_HDD_CONN_SER_TX8_N
REDV_I2C_SDA
REDV_I2C_SCL
3D3V
3D3V
3D3V
3D3V
3D3V
3D3V
3D3V 1D8V 1V 1D2V
3D3V
1D2V
3D3V
1D2V
SAS_I2C_A_SCL6
SAS_I2C_A_SDA6
LED_DR_LED0 16
SAS_I2C_A_SDA 6
SAS_I2C_A_SCL 6
SAS_I2C_A_SCL 6
SAS_I2C_A_SDA 6
SAS_HDD_REDV_TX7_P3
SAS_HDD_REDV_TX7_N3
SAS_HDD_REDV_TX8_P3
SAS_HDD_REDV_TX8_N3
SAS_HDD_CONN_TX7_P 11
SAS_HDD_CONN_TX7_N 11
SAS_HDD_CONN_TX8_P 11
SAS_HDD_CONN_TX8_N 11
SAS_HDD_CONN_RX8_P11
SAS_HDD_CONN_RX8_N11
SAS_HDD_CONN_RX7_P11
SAS_HDD_CONN_RX7_N11
SAS_HDD_REDV_RX8_N 3
SAS_HDD_REDV_RX8_P 3
SAS_HDD_REDV_RX7_N 3
SAS_HDD_REDV_RX7_P 3
SAS_I2C_A_SCL6
SAS_I2C_A_SDA6
Title
Size Document Number Rev
Date: Sheet
of
Honey_Badger_SEB 1
I2C_A DEVICES
A3
13 22Tuesday, April 07, 2015
Wiwynn
H/W R&D Dept. II
8F,90,Sec. 1,Hsin Tai Wu Rd,
Hsichih, Taipei Hsien 221, Taiwan, R.O.C
Title
Size Document Number Rev
Date: Sheet
of
Honey_Badger_SEB 1
I2C_A DEVICES
A3
13 22Tuesday, April 07, 2015
Wiwynn
H/W R&D Dept. II
8F,90,Sec. 1,Hsin Tai Wu Rd,
Hsichih, Taipei Hsien 221, Taiwan, R.O.C
Title
Size Document Number Rev
Date: Sheet
of
Honey_Badger_SEB 1
I2C_A DEVICES
A3
13 22Tuesday, April 07, 2015
Wiwynn
H/W R&D Dept. II
8F,90,Sec. 1,Hsin Tai Wu Rd,
Hsichih, Taipei Hsien 221, Taiwan, R.O.C
R308 0R2J-2-GPR308 0R2J-2-GP1 2
R319 0R2J-2-GPDYR319 0R2J-2-GPDY1 2
R147
4K7R2F-GP
R147
4K7R2F-GP
1 2
U5
24LC64T-I-GP
U5
24LC64T-I-GP
A12
A23
A01
SDA 5VSS4 SCL 6WP 7VCC 8
TP164
TPAD32-GP
TP164
TPAD32-GP
1
R124 
4K7R2F-GP 
R124 
4K7R2F-GP 
1 2
C213 
SCD1U16V2KX-3GP 
C213 
SCD1U16V2KX-3GP 
1 2
R242
4K7R2J-2-GP
R242
4K7R2J-2-GP
1 2
R240 
0R2J-2-GP 
R240 
0R2J-2-GP 
1 2
C226 
SCD1U16V2KX-3GP 
C226 
SCD1U16V2KX-3GP 
1 2
R286 0R2J-2-GPR286 0R2J-2-GP1 2
R317 0R2J-2-GPDYR317 0R2J-2-GPDY1 2
C205 
SC1U10V2KX-4-GP 
C205 
SC1U10V2KX-4-GP 
1 2 R215 
0R2J-2-GP 
R215 
0R2J-2-GP 
1 2
R283 0R2J-2-GPR283 0R2J-2-GP1 2
C225
SCD1U16V2KX-3GP
C225
SCD1U16V2KX-3GP
1 2
R185
4K7R2F-GP
DYR185
4K7R2F-GP
DY
1 2
R315 0R2J-2-GPR315 0R2J-2-GP1 2
C227 
SCD1U16V2KX-3GP 
C227 
SCD1U16V2KX-3GP 
1 2
R301 0R2J-2-GPDYR301 0R2J-2-GPDY1 2
R304 0R2J-2-GPDYR304 0R2J-2-GPDY1 2
R117 
4K7R2F-GP 
DY R117 
4K7R2F-GP 
DY 
1 2
R309 0R2J-2-GPDYR309 0R2J-2-GPDY1 2
R313 0R2J-2-GPDYR313 0R2J-2-GPDY1 2
R239 
0R2J-2-GP 
R239 
0R2J-2-GP 
1 2
C224
SC1U10V2KX-4-GP
C224
SC1U10V2KX-4-GP
1 2
R320 0R2J-2-GPDYR320 0R2J-2-GPDY1 2
TP150
TPAD32-GP
TP150
TPAD32-GP
1
U7
ADS1015IDGSR-GP
U7
ADS1015IDGSR-GP
ADDR 1
ALERT/RDY 2
GND 3
AIN04
AIN15
AIN26
AIN37
VDD8
SDA 9SCL 10
R287 0R2J-2-GPR287 0R2J-2-GP1 2
R153 0R2J-2-GPR153 0R2J-2-GP1 2
R149 0R2J-2-GPR149 0R2J-2-GP1 2
R128
0R2J-2-GP
R128
0R2J-2-GP
1 2
R140 
4K7R2F-GP 
DY R140 
4K7R2F-GP 
DY 
1 2
C228 
SCD1U16V2KX-3GP 
C228 
SCD1U16V2KX-3GP 
1 2
R241 
0R2J-2-GP 
R241 
0R2J-2-GP 
1 2
R155
4K7R2F-GP
DYR155
4K7R2F-GP
DY
1 2
R116 
4K7R2F-GP 
DY R116 
4K7R2F-GP 
DY 
1 2
R144 
4K7R2F-GP 
R144 
4K7R2F-GP 
1 2
R294 0R2J-2-GPDYR294 0R2J-2-GPDY1 2
C222 
SCD1U16V2KX-3GP 
C222 
SCD1U16V2KX-3GP 
1 2
R316 0R2J-2-GPR316 0R2J-2-GP1 2
R281 0R2J-2-GPR281 0R2J-2-GP1 2
U4
PI2EQX6812ZHE-GP
U4
PI2EQX6812ZHE-GP
VDD3
VDD14
VDD25
VDD30
VDD31
VDD8
VDD9
VDD36
GND 43
A0RX+ 4
A0RX- 5
A1RX+ 10
A1RX- 11
B0RX- 32B0RX+ 33
B1RX- 26B1RX+ 27
A0TX- 34A0TX+ 35
A1TX- 28A1TX+ 29
B0TX+ 6
B0TX- 7
B1TX+ 12
B1TX- 13D1_B19
D2_B16
SCL39 SDA38 PD# 37
MODE 15
NC#2 2
NC#18 18
NC#20 20
A021
A122
A417
D1_A41
D2_A40
SEL1A1
SEL2A42
SEL1B24
SEL2B23
R284 0R2J-2-GPR284 0R2J-2-GP1 2
C223 
SCD01U50V2KX-1GP 
C223 
SCD01U50V2KX-1GP 
1 2
U6
PCA9550DP-1-GP
U6
PCA9550DP-1-GP
A01
LED0 2
LED1 3
VSS 4
RESET#5
SCL6
SDA7
VDD 8
R118 
4K7R2F-GP 
DY R118 
4K7R2F-GP 
DY 
1 2
R125
0R2J-2-GP
R125
0R2J-2-GP
1 2
R310 0R2J-2-GPDYR310 0R2J-2-GPDY1 2
C306 SC10U6D3V5KX-4GP C306 SC10U6D3V5KX-4GP 
1 2
C221 
SCD01U50V2KX-1GP 
C221 
SCD01U50V2KX-1GP 
1 2
R145 
4K7R2F-GP 
R145 
4K7R2F-GP 
1 2
R311 0R2J-2-GPDYR311 0R2J-2-GPDY1 2
C229 
SCD1U16V2KX-3GP 
C229 
SCD1U16V2KX-3GP 
1 2
R123 
4K7R2F-GP 
R123 
4K7R2F-GP 
1 2
R139 
4K7R2F-GP 
DY R139 
4K7R2F-GP 
DY 
1 2
R148 0R2J-2-GPR148 0R2J-2-GP1 2
R288 0R2J-2-GPR288 0R2J-2-GP1 2
R115 
4K7R2F-GP 
R115 
4K7R2F-GP 
1 2
R318 0R2J-2-GPDYR318 0R2J-2-GPDY1 2
R150 
100KR2F-L1-GP 
R150 
100KR2F-L1-GP 
1 2
R122 
4K7R2F-GP 
DY R122 
4K7R2F-GP 
DY 
1 2
R127
0R2J-2-GP
R127
0R2J-2-GP
1 2
R307 0R2J-2-GPR307 0R2J-2-GP1 2
R141 
4K7R2F-GP 
DY R141 
4K7R2F-GP 
DY 
1 2
R146 
4K7R2F-GP 
R146 
4K7R2F-GP 
1 2
R154
4K7R2F-GP
R154
4K7R2F-GP
1 2
R312 0R2J-2-GPR312 0R2J-2-GP1 2
R289 0R2J-2-GPR289 0R2J-2-GP1 2
R285 0R2J-2-GPR285 0R2J-2-GP1 2
R305 0R2J-2-GPDYR305 0R2J-2-GPDY1 2
TP165
TPAD32-GP
TP165
TPAD32-GP
1
R126
0R2J-2-GP
R126
0R2J-2-GP
1 2
R143 
4K7R2F-GP 
R143 
4K7R2F-GP 
1 2
R120 
4K7R2F-GP 
R120 
4K7R2F-GP 
1 2
TP49 TPAD32-GPTP49 TPAD32-GP1
R152 0R2J-2-GPR152 0R2J-2-GP1 2
C211 
SCD1U16V2KX-3GP 
C211 
SCD1U16V2KX-3GP 
1 2
R142 
4K7R2F-GP 
R142 
4K7R2F-GP 
1 2 R253
4K7R2F-GP
DYR253
4K7R2F-GP
DY
1 2
R290 0R2J-2-GPR290 0R2J-2-GP1 2
R119 
4K7R2F-GP 
R119 
4K7R2F-GP 
1 2
R282 0R2J-2-GPR282 0R2J-2-GP1 2
C210 
SCD1U16V2KX-3GP 
C210 
SCD1U16V2KX-3GP 
1 2
R138 
4K7R2F-GP 
DY R138 
4K7R2F-GP 
DY 
1 2
C220 
SCD1U16V2KX-3GP 
C220 
SCD1U16V2KX-3GP 
1 2
R151 
100KR2F-L1-GP 
R151 
100KR2F-L1-GP 
1 2
R303 0R2J-2-GPDYR303 0R2J-2-GPDY1 2
R302 0R2J-2-GPR302 0R2J-2-GP1 2
R121
0R2J-2-GP
R121
0R2J-2-GP
1 2
R314 0R2J-2-GPDYR314 0R2J-2-GPDY1 2
R306 0R2J-2-GPDYR306 0R2J-2-GPDY1 2
R293 0R2J-2-GPDYR293 0R2J-2-GPDY1 2
R263
0R5J-5-GP
R263
0R5J-5-GP
1 2
C212 
SCD1U16V2KX-3GP 
C212 
SCD1U16V2KX-3GP 
1 2



5
5
4
4
3
3
2
2
1
1
D D
C C
B B
A A
I2C_C BUFFER
ADD=1001000 (0x90)-->A1=000
ADD=1001001 (0x92)-->B1=001
ADD=1001010 (0x94)-->A2=010
ADD=1001011 (0x96)-->B2=011
I2C_B BUFFER
TEMP SENSOR 1
TEMP SENSOR 2
I2C_D BUFFER
ADD=0011100 (0x98)-->A3=01
ADD=1001110 (0x9C)-->B3=11
EXP TEMP SENSOR
Temp_2_A1
Temp_2_A2
Temp_2_SDA
Temp_2_SCL
Temp_2_ALERT
Temp_1_A1
Temp_1_A2
Temp_1_SCL
Temp_1_ALERT
Temp_1_SDA
I2C_B_BUFF_EN
I2C_B_BUF_READY
I2C_C_BUFF_EN
I2C_C_BUF_READY
Temp_1_A0
Temp_2_A0
I2C_D_BUF_READY
SAS_I2C_D_SDA
SAS_I2C_D_BUF_SDASAS_I2C_D_BUF_SCL
SAS_I2C_D_SCL
I2C_D_BUFF_EN
EXP_TEMP_SCL
EXP_TEMP_SDA
EXP_TEMP_ALERT
EXP_TEMP_A0
TMP400_STBY#
SAS_TDIODE_P
SAS_TDIODE_VSS
SAS_I2C_C_SCLSAS_I2C_C_BUF_SCL
SAS_I2C_C_BUF_SDA SAS_I2C_C_SDA
SAS_I2C_B_BUF_SCL
SAS_I2C_B_SCL SAS_I2C_B_SDA
SAS_I2C_B_BUF_SDA
SAS_I2C_C_BUF_SCL
SAS_I2C_C_SCL
SAS_I2C_C_BUF_SDA
SAS_I2C_C_SDA
3D3V
3D3V
3D3V
3D3V
3D3V
3D3V
3D3V
3D3V
3D3V
3D3V
3D3V
3D3V
3D3V
3D3V
3D3V
3D3V
3D3V
3D3V
SAS_I2C_D_SCL6
SAS_I2C_D_SDA6
Temp_1_A0 11
Temp_2_A0 11
SAS_I2C_D_BUF_SDA 11
SAS_I2C_D_SDA 6
SAS_I2C_D_BUF_SCL11
SAS_I2C_D_SCL6
SAS_TDIODE_P 5
SAS_TDIODE_VSS 5
EXP_TEMP_A1 11
SAS_I2C_B_BUF_SCL11
SAS_I2C_B_SCL6
SAS_I2C_B_BUF_SDA 11
SAS_I2C_B_SDA 6
SAS_I2C_C_SCL6
SAS_I2C_C_BUF_SCL11
SAS_I2C_C_SDA 6
SAS_I2C_C_BUF_SDA 11
Title
Size Document Number Rev
Date: Sheet
of
Honey_Badger_SEB 1
I2C_B&C&D DEVICES
A3
14 22Tuesday, April 07, 2015
Wiwynn
H/W R&D Dept. II
8F,90,Sec. 1,Hsin Tai Wu Rd,
Hsichih, Taipei Hsien 221, Taiwan, R.O.C
Title
Size Document Number Rev
Date: Sheet
of
Honey_Badger_SEB 1
I2C_B&C&D DEVICES
A3
14 22Tuesday, April 07, 2015
Wiwynn
H/W R&D Dept. II
8F,90,Sec. 1,Hsin Tai Wu Rd,
Hsichih, Taipei Hsien 221, Taiwan, R.O.C
Title
Size Document Number Rev
Date: Sheet
of
Honey_Badger_SEB 1
I2C_B&C&D DEVICES
A3
14 22Tuesday, April 07, 2015
Wiwynn
H/W R&D Dept. II
8F,90,Sec. 1,Hsin Tai Wu Rd,
Hsichih, Taipei Hsien 221, Taiwan, R.O.C
R359
0R2J-2-GP
DYR359
0R2J-2-GP
DY
1 2
C235 
SCD1U16V2KX-3GP 
C235 
SCD1U16V2KX-3GP 
1 2
R358
0R2J-2-GP
R358
0R2J-2-GP 1 2
C307 
SC220P50V3JN-GP 
DY
C307 
SC220P50V3JN-GP 
DY
1 2
R165
0R2J-2-GP
R165
0R2J-2-GP
1 2
C231 
SCD1U16V2KX-3GP 
C231 
SCD1U16V2KX-3GP 
1 2
C232 
SCD01U50V2KX-1GP 
C232 
SCD01U50V2KX-1GP 
1 2
R234 
4K7R2F-GP 
DY R234 
4K7R2F-GP 
DY 
1 2
U16
PCA9511ADP-T-GP
U16
PCA9511ADP-T-GP
ENABLE1
SCLOUT2
SCLIN3
GND4 READY 5SDAIN 6SDAOUT 7VCC 8
U21
TMP400AIDBQR-GP
U21
TMP400AIDBQR-GP
NC#11
V+ 2
D+ 3
D- 4NC#55
A1 6
GND7
GND8
NC#1616
STBY# 15
SCL14
NC#1313
SDA12
ALERT# 11
A0 10NC#99
R174
2KR2F-3-GP
DY
R174
2KR2F-3-GP
DY
1 2
R170 
4K7R2F-GP 
R170 
4K7R2F-GP 
1 2
R244 
4K7R2F-GP 
R244 
4K7R2F-GP 
1 2
TP151
TPAD32-GP
TP151
TPAD32-GP
1
C310 
SC220P50V3JN-GP 
DY
C310 
SC220P50V3JN-GP 
DY1 2
R162 
4K7R2J-2-GP 
DY R162 
4K7R2J-2-GP 
DY 
1 2
C250 
SCD1U16V2KX-3GP 
C250 
SCD1U16V2KX-3GP 
1 2
C202 
SC2200P50V2KX-2GP 
C202 
SC2200P50V2KX-2GP 
1 2
R157
0R2J-2-GP
R157
0R2J-2-GP
1 2
R159 
4K7R2F-GP 
DY R159 
4K7R2F-GP 
DY 
1 2
R169
0R2J-2-GP
R169
0R2J-2-GP
1 2
R173
10KR2F-2-GP
R173
10KR2F-2-GP
1 2
C234 
SCD01U50V2KX-1GP 
C234 
SCD01U50V2KX-1GP 
1 2
R249 
4K7R2J-2-GP 
DY R249 
4K7R2J-2-GP 
DY 
1 2
R250 
4K7R2J-2-GP 
DY R250 
4K7R2J-2-GP 
DY 
1 2
R172
2KR2F-3-GP
DY
R172
2KR2F-3-GP
DY
1 2
R161 
4K7R2F-GP 
R161 
4K7R2F-GP 
1 2
C251 
SCD01U50V2KX-1GP 
C251 
SCD01U50V2KX-1GP 
1 2
R164 
4K7R2J-2-GP 
DY R164 
4K7R2J-2-GP 
DY 
1 2
R357
0R2J-2-GP
R357
0R2J-2-GP 1 2
R166
10KR2F-2-GP
R166
10KR2F-2-GP
1 2
R248
10KR2F-2-GP
R248
10KR2F-2-GP
1 2
C309 
SC220P50V3JN-GP 
DY
C309 
SC220P50V3JN-GP 
DY
1 2
R171 
4K7R2F-GP 
DY R171 
4K7R2F-GP 
DY 
1 2
TP152
TPAD32-GP
TP152
TPAD32-GP
1
R233 
4K7R2F-GP 
DY R233 
4K7R2F-GP 
DY 
1 2
R156
0R2J-2-GP
R156
0R2J-2-GP
1 2
C233 
SCD1U16V2KX-3GP 
C233 
SCD1U16V2KX-3GP 
1 2
R160 
4K7R2F-GP 
R160 
4K7R2F-GP 
1 2
U8
TMP75AIDGKT-GP
U8
TMP75AIDGKT-GP
SDA1
SCL2
ALERT3
GND4 A2 5A1 6A0 7V+ 8
R321
10KR2F-2-GP
R321
10KR2F-2-GP
1 2
U9
PCA9511ADP-T-GP
U9
PCA9511ADP-T-GP
ENABLE1
SCLOUT2
SCLIN3
GND4 READY 5SDAIN 6SDAOUT 7VCC 8
R360
0R2J-2-GP
DYR360
0R2J-2-GP
DY
1 2
R175
10KR2F-2-GP
R175
10KR2F-2-GP
1 2
R158 
4K7R2F-GP 
DY R158 
4K7R2F-GP 
DY 
1 2
C230 
SCD1U16V2KX-3GP 
C230 
SCD1U16V2KX-3GP 
1 2
C255 
SCD1U16V2KX-3GP 
C255 
SCD1U16V2KX-3GP 
1 2
C308 
SC220P50V3JN-GP 
DY
C308 
SC220P50V3JN-GP 
DY
1 2
U10
TMP75AIDGKT-GP
U10
TMP75AIDGKT-GP
SDA1
SCL2
ALERT3
GND4 A2 5A1 6A0 7V+ 8
R168 
4K7R2F-GP 
R168 
4K7R2F-GP 
1 2
U11
PCA9511ADP-T-GP
U11
PCA9511ADP-T-GP
ENABLE1
SCLOUT2
SCLIN3
GND4 READY 5SDAIN 6SDAOUT 7VCC 8
R167 
4K7R2F-GP 
DY R167 
4K7R2F-GP 
DY 
1 2
R251
10KR2F-2-GP
R251
10KR2F-2-GP
1 2
R163
10KR2F-2-GP
R163
10KR2F-2-GP
1 2
R324 
4K7R2F-GP 
R324 
4K7R2F-GP 
1 2



5
5
4
4
3
3
2
2
1
1
D D
C C
B B
A A
SYSTEM RESET
ICE CONN
MDIO EYE FINDER
3.5uA
DEBUG CARD HEADER
RST IC_SRT
RST IC_VCCRST IC_RST_IN
1D8V_RST_IN 1D8V_RST_IN_R
DBC_DETECTIONDEBUG_RESET#
SAS_SMART_TX_CONN SAS_SMART_RX_CONN
SAS_ICE_TRST#
SAS_ICE_TDI
SAS_ICE_TMS
SAS_ICE_TCK
SAS_ICE_RTCK
SAS_ICE_TDO
ICE_RESET#
3D3V_ICE
SAS_SDBTX_SW
SAS_SDBRX_SW
SAS_SMART_TX_CONN
SAS_SMART_RX_CONN
SMART_DEBUG_SW
SAS_SMART_RX
SAS_SMART_TX
SAS_SDBTX_SW
SAS_SDBRX_SW
1D8V
3D3V
3D3V
3D3V
5V
3D3V
3D3V3D3V
3D3V
3D3V
RESET IC_RESET# 5,9
SAS_SMART_TX6 SAS_SMART_RX 6
MDIO_CLK5
MDIO_DATA5
RESET IC_RESET#5,9
SAS_GPIO9 5
SAS_GPIO8 5
SAS_ICE_TRST#5
SAS_ICE_TDI5
SAS_ICE_TMS5
SAS_ICE_TCK5
SAS_ICE_TDO5
SAS_ICE_RTCK5
RESET IC_RESET#5,9
SAS_Activity_LED175 SAS_Activity_LED18 5
SAS_Activity_LED195
SAS_Status_LED915
SAS_Status_LED895 SAS_Status_LED90 5
SAS_SDBRX 6
SAS_SDBTX 6
Title
Size Document Number Rev
Date: Sheet
of
Honey_Badger_SEB 1
DEBUG&RESET
A3
15 22Tuesday, April 07, 2015
Wiwynn
H/W R&D Dept. II
8F,90,Sec. 1,Hsin Tai Wu Rd,
Hsichih, Taipei Hsien 221, Taiwan, R.O.C
Title
Size Document Number Rev
Date: Sheet
of
Honey_Badger_SEB 1
DEBUG&RESET
A3
15 22Tuesday, April 07, 2015
Wiwynn
H/W R&D Dept. II
8F,90,Sec. 1,Hsin Tai Wu Rd,
Hsichih, Taipei Hsien 221, Taiwan, R.O.C
Title
Size Document Number Rev
Date: Sheet
of
Honey_Badger_SEB 1
DEBUG&RESET
A3
15 22Tuesday, April 07, 2015
Wiwynn
H/W R&D Dept. II
8F,90,Sec. 1,Hsin Tai Wu Rd,
Hsichih, Taipei Hsien 221, Taiwan, R.O.C
C253 
SCD1U16V2KX-3GP 
C253 
SCD1U16V2KX-3GP 
1 2
R188
56K2R2F-2-GP
R188
56K2R2F-2-GP
1 2
R245
0R2J-2-GP
R245
0R2J-2-GP
1 2
CN10
MLX-CONN20A-S3-GP
DYCN10
MLX-CONN20A-S3-GP
DY
1
3
5
7
9
11
13
15
17
19
2
4
6
8
10
12
14
16
18
20
CN5
SMC-CONN14A-3-GP
CN5
SMC-CONN14A-3-GP
1
3
5
7
9
11
2
4
6
8
10
12
13 14
TP162 TPAD32-GPTP162 TPAD32-GP1
R182 
4K75R2F-1-GP 
R182 
4K75R2F-1-GP 
1 2
R226
0R2J-2-GP
R226
0R2J-2-GP
1 2
R189 
4K75R2F-1-GP 
R189 
4K75R2F-1-GP 
1 2
R186 
4K75R2F-1-GP 
R186 
4K75R2F-1-GP 
1 2
R191
182KR2F-GP
R191
182KR2F-GP
1 2
R232 0R2J-2-GPR232 0R2J-2-GP1 2
R194 
4K75R2F-1-GP 
DY R194 
4K75R2F-1-GP 
DY 
1 2
R187
0R2J-2-GP DY
R187
0R2J-2-GP DY
1 2
R192
0R2J-2-GP
DYR192
0R2J-2-GP
DY
1 2
R203
0R2J-2-GP
DYR203
0R2J-2-GP
DY1 2
R262
0R3J-0-U-GP
R262
0R3J-0-U-GP
1 2
R195 
4K75R2F-1-GP 
DY R195 
4K75R2F-1-GP 
DY 
1 2
R180
0R2J-2-GP
R180
0R2J-2-GP
1 2
R230 0R2J-2-GPR230 0R2J-2-GP1 2
C245 
SCD1U16V2KX-3GP 
C245 
SCD1U16V2KX-3GP 
1 2
R181
1KR2F-3-GP
R181
1KR2F-3-GP
1 2
C237 
SCD1U16V2KX-3GP 
C237 
SCD1U16V2KX-3GP 
1 2
C249 
SCD1U16V2KX-3GP 
C249 
SCD1U16V2KX-3GP 
1 2
R202
0R2J-2-GP
DYR202
0R2J-2-GP
DY1 2
C305
SCD1U16V2KX-3GP
C305
SCD1U16V2KX-3GP
1 2
U20
TS5A23157DGSR-GP
U20
TS5A23157DGSR-GP
IN11
NO1 2
GND 3
NO2 4IN25
COM26
NC2 7V+8 NC1 9
COM110
R184 
4K75R2F-1-GP 
R184 
4K75R2F-1-GP 
1 2
R199
4K75R2F-1-GP
R199
4K75R2F-1-GP
1 2
L65
BLM15HD102SN1D-GP
L65
BLM15HD102SN1D-GP
1 2
TP163 TPAD32-GPTP163 TPAD32-GP1
R183 
4K75R2F-1-GP 
R183 
4K75R2F-1-GP 
1 2
C239
SCD01U50V2KX-1GP
C239
SCD01U50V2KX-1GP
1 2
C238
SCD1U16V2KX-3GP
C238
SCD1U16V2KX-3GP
1 2
U13
MAX6420UK29-T-GP
U13
MAX6420UK29-T-GP
RST IN3
SRT4
VCC 5
GND 2
RESET# 1
R193
1KR2F-3-GP
R193
1KR2F-3-GP
1 2



5
5
4
4
3
3
2
2
1
1
D D
C C
B B
A A
HEARTBEAT CIRCUITRY
2.8V
0.5V INT MINISAS_B LED
ENCLOSURE STATUS_LED
INT MINISAS_A LED
EXT MINISAS LED
AND GATE
Divider 1_IN
HB_A_OUT
Inverter_G1
HB_A_IN
INTA_LED_RED_B
EXT_LED_RED_B
EXT_LED_GND
INTB_LED_BLUE_B
INTB_LED_GND
INTB_LED_BLUE_C
INTB_LED_RED_C
INTA_LED_BLUE_B
ENCLO_LED_RED_B
ENCLO_LED_BLUE_B
ENCLO_LED_GND
ENCLO_LED_BLUE_OUT
ENCLO_LED_BLUE_C
ENCLO_LED_RED_C
EXT_LED_BLUE_C
EXT_LED_BLUE_B
INTA_LED_GND
INTA_LED_BLUE_C
INTA_LED_RED_C
EXT_LED_RED_C
INTB_LED_RED_B
Divider 2_IN
SHUTDOWN_RELEASE
Inverter_G2Inverter_G2
3D3V
3D3V
3D3V
3D3V
12V
3D3V
3D3V
3D3V
3D3V
3D3V
3D3V
3D3V
3D3V
3D3V
12V
12V
12V
3D3V
3D3V
SAS_GPIO25
HB_OUT 11
SAS_Status_LED88 5
SAS_Activity_LED24 5
SAS_Activity_LED16 5
SAS_Activity_LED20 5
SAS_Status_LED96 5
SAS_Status_LED92 5
SAS_GPIO7 5
HB_OUT11
LED_DR_LED013
SHUTDOWN_RELEASE11
Title
Size Document Number Rev
Date: Sheet
of
Honey_Badger_SEB 1
LEDs&HB
A3
16 22Tuesday, April 07, 2015
Wiwynn
H/W R&D Dept. II
8F,90,Sec. 1,Hsin Tai Wu Rd,
Hsichih, Taipei Hsien 221, Taiwan, R.O.C
Title
Size Document Number Rev
Date: Sheet
of
Honey_Badger_SEB 1
LEDs&HB
A3
16 22Tuesday, April 07, 2015
Wiwynn
H/W R&D Dept. II
8F,90,Sec. 1,Hsin Tai Wu Rd,
Hsichih, Taipei Hsien 221, Taiwan, R.O.C
Title
Size Document Number Rev
Date: Sheet
of
Honey_Badger_SEB 1
LEDs&HB
A3
16 22Tuesday, April 07, 2015
Wiwynn
H/W R&D Dept. II
8F,90,Sec. 1,Hsin Tai Wu Rd,
Hsichih, Taipei Hsien 221, Taiwan, R.O.C
RED 
ANODE 
COMMON CATHODE 
BLUE 
ANODE 
LED9
LED-RB-6-GP
RED 
ANODE 
COMMON CATHODE 
BLUE 
ANODE 
LED9
LED-RB-6-GP 1
2
3
SW1
SW-TACT-4P-52-GP
SW1
SW-TACT-4P-52-GP
1 2
3 4
R258
1K8R6J-GP
R258
1K8R6J-GP
1 2
R361
51R2010F-GP
DY
R361
51R2010F-GP
DY
1 2
R223 
49D9R2F-GP 
DY
R223 
49D9R2F-GP 
DY
1 2
R221 
49D9R2F-GP 
DY
R221 
49D9R2F-GP 
DY
1 2
R333
1KR2F-3-GP
DYR333
1KR2F-3-GP
DY
1 2
R346
1KR2F-3-GP
R346
1KR2F-3-GP
1 2
R222
300R3F-GP
R222
300R3F-GP
1 2
R322
1KR2F-3-GP
DYR322
1KR2F-3-GP
DY
1 2
+
-
U15B
LM393ADR-1-GP
+
-
U15B
LM393ADR-1-GP
5
6
7
8 4
Q4
PMBS3904-1-GP
Q4
PMBS3904-1-GP
3
1
2
R336
0R2J-2-GP
R336
0R2J-2-GP
1 2
R214
4K7R2F-GP
R214
4K7R2F-GP
1 2
R344
1K8R6J-GP
R344
1K8R6J-GP
1 2
+
-
U15A
LM393ADR-1-GP
+
-
U15A
LM393ADR-1-GP
3
2
1
8 4
R323
0R2J-2-GP
R323
0R2J-2-GP
1 2
R334
1KR2F-3-GP
DYR334
1KR2F-3-GP
DY
1 2
R337
1KR2F-3-GP
R337
1KR2F-3-GP
1 2
Q2
PMBS3904-1-GP
Q2
PMBS3904-1-GP
3
1
2
RED 
ANODE 
COMMON CATHODE 
BLUE 
ANODE 
LED5
LED-RB-6-GP
RED 
ANODE 
COMMON CATHODE 
BLUE 
ANODE 
LED5
LED-RB-6-GP 1
2
3
R325
1KR2F-3-GP
R325
1KR2F-3-GP
1 2
R220 
49D9R2F-GP 
DY
R220 
49D9R2F-GP 
DY
1 2
R338
1KR2F-3-GP
R338
1KR2F-3-GP
1 2
R329
1KR2F-3-GP
DYR329
1KR2F-3-GP
DY
1 2
C304 
SC1U10V2KX-1GP 
C304 
SC1U10V2KX-1GP 
1 2
Q6
PMBS3904-1-GP
Q6
PMBS3904-1-GP
3
1
2
R328
1KR2F-3-GP
DYR328
1KR2F-3-GP
DY
1 2
Q5
PMBS3904-1-GP
Q5
PMBS3904-1-GP
3
1
2
R211
200R3F-GP
R211
200R3F-GP
1 2
R343
0R2J-2-GP
R343
0R2J-2-GP
1 2
R213
10KR2F-2-GP
DYR213
10KR2F-2-GP
DY
1 2R210
1KR2F-3-GP
R210
1KR2F-3-GP
1 2
R347
1K8R6J-GP
R347
1K8R6J-GP
1 2
C248
SCD1U16V2KX-3GP
C248
SCD1U16V2KX-3GP
1 2
RED 
ANODE 
COMMON CATHODE 
BLUE 
ANODE 
LED7
LED-RB-6-GP
RED 
ANODE 
COMMON CATHODE 
BLUE 
ANODE 
LED7
LED-RB-6-GP 1
2
3
R227 
49D9R2F-GP 
DY
R227 
49D9R2F-GP 
DY
1 2
R340
1KR2F-3-GP
R340
1KR2F-3-GP
1 2
R345
1KR2F-3-GP
R345
1KR2F-3-GP
1 2
R237
0R2J-2-GP
DY
R237
0R2J-2-GP
DY
1 2
R330
1KR2F-3-GP
R330
1KR2F-3-GP
1 2
Q9
PMBS3904-1-GP
Q9
PMBS3904-1-GP
3
1
2
R296
0R2J-2-GP
R296
0R2J-2-GP
1 2
Q3
PMBS3904-1-GP
Q3
PMBS3904-1-GP
3
1
2
R212
2MR2F-GP
R212
2MR2F-GP
1 2
RED 
ANODE 
COMMON CATHODE 
BLUE 
ANODE 
LED6
LED-RB-6-GP
RED 
ANODE 
COMMON CATHODE 
BLUE 
ANODE 
LED6
LED-RB-6-GP 1
2
3
Q7
PMBS3904-1-GP
Q7
PMBS3904-1-GP
3
1
2
R219
300R3F-GP
R219
300R3F-GP
1 2
R216
1KR2F-3-GP
R216
1KR2F-3-GP
1 2
R326
1KR2F-3-GP
R326
1KR2F-3-GP
1 2
R348
1KR2F-3-GP
DYR348
1KR2F-3-GP
DY
1 2
Q10
2N7002DW-7F-GP
DY
Q10
2N7002DW-7F-GP
DY
1
2
3 4
5
6
R217
0R2J-2-GP
R217
0R2J-2-GP
1 2
U19
74LVC1G08GW-1-GP
U19
74LVC1G08GW-1-GP
B1
A2
GND3 Y 4
VCC 5
R295
1KR2F-3-GP
DYR295
1KR2F-3-GP
DY
1 2
R218
300R3F-GP
R218
300R3F-GP
1 2
Q8
PMBS3904-1-GP
Q8
PMBS3904-1-GP
3
1
2
C246
SCD1U16V2KX-3GP
C246
SCD1U16V2KX-3GP
1 2
R225
300R3F-GP
R225
300R3F-GP
1 2
R339
1KR2F-3-GP
DYR339
1KR2F-3-GP
DY
1 2
R341
1K8R6J-GP
R341
1K8R6J-GP
1 2



5
5
4
4
3
3
2
2
1
1
D D
C C
B B
A A
1D2V LDO TPS74801
5V RERULATOR
1D8V LDO TPS74801
TPS74801_1V2_BIAS
TPS74801_1V2_IN TPS74801_1V2_OUT
TPS74801_1V2_FB
1D2V_LDO_PG
TPS74801_1V2_EN
TPS74801_1V2_SS
TPS74801_1V8_IN
TPS74801_1V8_BIAS
TPS74801_1V8_FB
TPS74801_1V8_EN
TPS74801_1V8_SS
1D8V_LDO_PG
TPS74801_1V8_OUT
78M05_12V_IN TPS74801_1V2_BIAS
TPS74801_1V8_BIAS
78M05_5V_OUT
5V_VREG
3D3V
3D3V
3D3V
1D8V
5V_VREG
5V
12V
5V
1D2V
1V_SWITCHING_PG18
1D8V_LDO_PG 19
Title
Size Document Number Rev
Date: Sheet
of
Honey_Badger_SEB 1
1D2V&1D8V_TPS74801
A3
17 22Tuesday, April 07, 2015
Wiwynn
H/W R&D Dept. II
8F,90,Sec. 1,Hsin Tai Wu Rd,
Hsichih, Taipei Hsien 221, Taiwan, R.O.C
Title
Size Document Number Rev
Date: Sheet
of
Honey_Badger_SEB 1
1D2V&1D8V_TPS74801
A3
17 22Tuesday, April 07, 2015
Wiwynn
H/W R&D Dept. II
8F,90,Sec. 1,Hsin Tai Wu Rd,
Hsichih, Taipei Hsien 221, Taiwan, R.O.C
Title
Size Document Number Rev
Date: Sheet
of
Honey_Badger_SEB 1
1D2V&1D8V_TPS74801
A3
17 22Tuesday, April 07, 2015
Wiwynn
H/W R&D Dept. II
8F,90,Sec. 1,Hsin Tai Wu Rd,
Hsichih, Taipei Hsien 221, Taiwan, R.O.C
PR10
10KR2F-2-GP
PR10
10KR2F-2-GP
1 2
PR8
4K7R2F-GP
PR8
4K7R2F-GP
1 2
PR61
0R1206-PAD-1-GP
PR61
0R1206-PAD-1-GP
1 2
PC47 
SC10U25V5KX-GP 
PC47 
SC10U25V5KX-GP 
1 2
PC4
SC10U6D3V5KX-4GP
PC4
SC10U6D3V5KX-4GP
1 2
PR3
2K37R2F-GP
PR3
2K37R2F-GP
1 2
PR2
10KR2F-2-GP
PR2
10KR2F-2-GP
1 2
PC50 
SC10U16V6KX-2GP 
DY PC50 
SC10U16V6KX-2GP 
DY 
1 2
PR11
3K57R2F-GP
PR11
3K57R2F-GP
1 2
PC7 
SC10U16V6KX-2GP 
PC7 
SC10U16V6KX-2GP 
1 2
PC2 
SC10U16V6KX-2GP 
PC2 
SC10U16V6KX-2GP 
1 2
PR58
0R1206-PAD-1-GP
PR58
0R1206-PAD-1-GP
1 2
PR14
0R2J-2-GP
PR14
0R2J-2-GP
1 2
PR59
0R1206-PAD-1-GP
PR59
0R1206-PAD-1-GP
1 2
PU2
TPS74801RGW-GP
PU2
TPS74801RGW-GP
OUT#1 1
NC#2 2
NC#3 3
NC#4 4
IN#55 IN#66 IN#77 IN#88
PG 9
BIAS 10 
EN 11 
GND 12 
NC#13 13 
NC#14 14 
SS 15 
FB 16 
NC#17 17 
OUT#18 18
OUT#19 19
OUT#20 20
GND 21 
PC9
SC10U6D3V5KX-4GP
PC9
SC10U6D3V5KX-4GP
1 2
PC8 
SC10U16V6KX-2GP 
PC8 
SC10U16V6KX-2GP 
1 2
PU1
TPS74801RGW-GP
PU1
TPS74801RGW-GP
OUT#1 1
NC#2 2
NC#3 3
NC#4 4
IN#55 IN#66 IN#77 IN#88
PG 9
BIAS 10 
EN 11 
GND 12 
NC#13 13 
NC#14 14 
SS 15 
FB 16 
NC#17 17 
OUT#18 18
OUT#19 19
OUT#20 20
GND 21 
PC46
SC470P50V2KX-3GP
PC46
SC470P50V2KX-3GP
1 2
PC10
SC10U6D3V5KX-4GP
PC10
SC10U6D3V5KX-4GP
1 2
PR56
0R1206-PAD-1-GP
PR56
0R1206-PAD-1-GP
1 2
PR1
0R2J-L-GP
DY
PR1
0R2J-L-GP
DY
1 2
PC48 
SC4D7U25V5KX-GP 
PC48 
SC4D7U25V5KX-GP 
1 2
TP40 TPAD32-GPTP40 TPAD32-GP1
PR57
0R1206-PAD-1-GP
PR57
0R1206-PAD-1-GP
1 2
PC45
SC470P50V2KX-3GP
PC45
SC470P50V2KX-3GP
1 2
PC3
SC10U6D3V5KX-4GP
PC3
SC10U6D3V5KX-4GP
1 2
PR4
0R2J-L-GP
DY
PR4
0R2J-L-GP
DY
1 2
PC6
SCD1U16V2KX-3GP
PC6
SCD1U16V2KX-3GP
1 2
PC11
SCD1U16V2KX-3GP
PC11
SCD1U16V2KX-3GP
1 2
PR13
2K87R2F-1-GP
PR13
2K87R2F-1-GP
1 2
PR9
0R2J-2-GP
PR9
0R2J-2-GP
1 2
TP32TPAD32-GP TP32TPAD32-GP 1
PC1 
SC10U16V6KX-2GP 
PC1 
SC10U16V6KX-2GP 
1 2
PC52 
SCD1U25V2KX-GP 
PC52 
SCD1U25V2KX-GP 
1 2
PR15
20KR2F-L-GP
PR15
20KR2F-L-GP
1 2
PR6
4K75R2F-1-GP
PR6
4K75R2F-1-GP
1 2
PC51 SC4D7U10V3KX-GP PC51 SC4D7U10V3KX-GP 
1 2
PR24
0R2J-2-GP
DY
PR24
0R2J-2-GP
DY1 2
PU6
UA78M05CDCYRG3-GP
PU6
UA78M05CDCYRG3-GP
OUTPUT 3COMMON 2INPUT 1
PC49 
SC1U25V3KX-1-GP 
PC49 
SC1U25V3KX-1-GP 
1 2
PR60
0R1206-PAD-1-GP
PR60
0R1206-PAD-1-GP
1 2



5
5
4
4
3
3
2
2
1
1
D D
C C
B B
A A
1V SWITCHING TPS53353
TPS53353_TRIP
TPS53353_RF
5V_VREG
TPS53353_VBST
1V_VFB_R
1V_LL_R1V_SNB
TPS53353_VFB
1V_LL
TPS53353_VIN
1V_VDD
TPS53353_EN
TPS53353_MODE MODE_PG
1V_VBST_RC
1V_SWITCHING_PG
TPS53353_AGND
TPS53353_AGND
5V_VREG
5V_VREG
3D3V_L
TPS53353_AGND
12V
1V
1V_SWITCHING_PG 17
Title
Size Document Number Rev
Date: Sheet
of
Honey_Badger_SEB 1
VCORE 1V_TPS53353
A3
18 22Tuesday, April 07, 2015
Wiwynn
H/W R&D Dept. II
8F,90,Sec. 1,Hsin Tai Wu Rd,
Hsichih, Taipei Hsien 221, Taiwan, R.O.C
Title
Size Document Number Rev
Date: Sheet
of
Honey_Badger_SEB 1
VCORE 1V_TPS53353
A3
18 22Tuesday, April 07, 2015
Wiwynn
H/W R&D Dept. II
8F,90,Sec. 1,Hsin Tai Wu Rd,
Hsichih, Taipei Hsien 221, Taiwan, R.O.C
Title
Size Document Number Rev
Date: Sheet
of
Honey_Badger_SEB 1
VCORE 1V_TPS53353
A3
18 22Tuesday, April 07, 2015
Wiwynn
H/W R&D Dept. II
8F,90,Sec. 1,Hsin Tai Wu Rd,
Hsichih, Taipei Hsien 221, Taiwan, R.O.C
PC26
SC1KP50V2KX-1GP
PC26
SC1KP50V2KX-1GP
1 2
PR30
10KR2D-GP
PR30
10KR2D-GP
1 2
PR26 
3D01R2F-GP 
PR26 
3D01R2F-GP 
1 2
PC16 
SC4D7U25V5KX-GP 
PC16 
SC4D7U25V5KX-GP 
1 2
PC14 
SC22U25V5MX-GP 
PC14 
SC22U25V5MX-GP 
1 2
PG1
COPPER-CLOSE-GP-U
PG1
COPPER-CLOSE-GP-U
1 2
TP46TPAD32-GP TP46TPAD32-GP 1
PC21 
SC100U6D3V0MX-2GP 
PC21 
SC100U6D3V0MX-2GP 
1 2
PC27
SCD1U25V2KX-GP
PC27
SCD1U25V2KX-GP
1 2
PR29
6K65R2D-GP
PR29
6K65R2D-GP
1 2
PC22 
SC100U6D3V0MX-2GP 
PC22 
SC100U6D3V0MX-2GP 
1 2
PL1
BLM41PG600-GP
PL1
BLM41PG600-GP
1 2
PL2
IND-1UH-196-GP
PL2
IND-1UH-196-GP
1 2
PR18
4K7R2F-GP
PR18
4K7R2F-GP
1 2
PC17
SC2200P50V2KX-2GP
PC17
SC2200P50V2KX-2GP
1 2
PR20
100KR2F-L1-GP
PR20
100KR2F-L1-GP
1 2
PC15 
SC22U25V5MX-GP 
PC15 
SC22U25V5MX-GP 
1 2
PC24 
SC100U6D3V0MX-2GP 
PC24 
SC100U6D3V0MX-2GP 
1 2
PR28 
0R2J-2-GP 
PR28 
0R2J-2-GP 
1 2
PR16
0R3J-0-U-GP
PR16
0R3J-0-U-GP
1 2
PC23 
SE470UF2VDM-GP 
PC23 
SE470UF2VDM-GP 
1 2
R228
10KR2F-2-GP
R228
10KR2F-2-GP
1 2
PC12 
SC22U25V5MX-GP 
PC12 
SC22U25V5MX-GP 
1 2
PR25 
866KR2F-GP 
DY PR25 
866KR2F-GP 
DY 
1 2
PC25
SC1U10V2KX-4-GP
PC25
SC1U10V2KX-4-GP
1 2
PR27
73K2R2F-GP
PR27
73K2R2F-GP
1 2
PR23
10R2F-L-GP
PR23
10R2F-L-GP
1 2PR22
3D01R2F-GP
PR22
3D01R2F-GP
12
PU3
TPS53353DQPR-GP
PU3
TPS53353DQPR-GP
VFB1
EN2
PGOOD 3
VBST4
NC#55
VIN12
VIN13
VIN14
VIN15
VIN16
VIN17
VREG18
VDD19
MODE 20
TRIP 21
RF 22
GND 23
LL#6 6
LL#7 7
LL#8 8
LL#9 9
LL#10 10
LL#11 11
PR17
10KR2F-2-GP
PR17
10KR2F-2-GP
1 2
PR19
10KR2F-2-GP
PR19
10KR2F-2-GP
1 2
PC18
SCD1U25V2KX-GP
PC18
SCD1U25V2KX-GP
1 2PR21
100KR2F-L1-GP
DY
PR21
100KR2F-L1-GP
DY
1 2
PC13 
SC22U25V5MX-GP 
PC13 
SC22U25V5MX-GP 
1 2
PC20 
SC100U6D3V0MX-2GP 
DY PC20 
SC100U6D3V0MX-2GP 
DY 
1 2



5
5
4
4
3
3
2
2
1
1
D D
C C
B B
A A
TPS2490 HOT SWAP PROTECTION
3D3V SWITCHING TPS54320
TPS2490_EN
12V_PWRGOOD
TPS2490_TIMER
TPS2490_VREF
TPS2490_PROG 
TPS2490_GATE 
TPS2490_GATE_MOS TPS2490_GATE_RC
TPS2490_DRAIN_MOS
TPS2490_SENSE
TPS2490_VCC
TPS54620_RT_CLK
TPS54620_SS_TR
TPS54620_VIN
TPS54620_PWRGD
TPS54620_BOOT
TPS54620_PH
TPS54620_COMP_RC1
TPS54620_VSENSE
TPS54620_EN
TPS54620_COMP_RC2 
TPS54620_COMP
PWR_SQ_C
PCIe_MATED#_BJT
12V
12V_PCIe
TPS54620_AGND
5V_VREG
12V
TPS54620_AGND
3D3V_L
12V
TPS54620_AGND
TPS54620_AGND
TPS54620_AGND
12V
3D3V
5V
12V
12V_PCIe
1D8V_LDO_PG 17
PCIe_MATED#11,12
Title
Size Document Number Rev
Date: Sheet
of
Honey_Badger_SEB 1
3D3V_TPS54620&TPS2490
A3
19 22Tuesday, April 07, 2015
Wiwynn
H/W R&D Dept. II
8F,90,Sec. 1,Hsin Tai Wu Rd,
Hsichih, Taipei Hsien 221, Taiwan, R.O.C
Title
Size Document Number Rev
Date: Sheet
of
Honey_Badger_SEB 1
3D3V_TPS54620&TPS2490
A3
19 22Tuesday, April 07, 2015
Wiwynn
H/W R&D Dept. II
8F,90,Sec. 1,Hsin Tai Wu Rd,
Hsichih, Taipei Hsien 221, Taiwan, R.O.C
Title
Size Document Number Rev
Date: Sheet
of
Honey_Badger_SEB 1
3D3V_TPS54620&TPS2490
A3
19 22Tuesday, April 07, 2015
Wiwynn
H/W R&D Dept. II
8F,90,Sec. 1,Hsin Tai Wu Rd,
Hsichih, Taipei Hsien 221, Taiwan, R.O.C
PL4
IND-4D7UH-315-GP
PL4
IND-4D7UH-315-GP
1 2
TP50
TPAD32-GP
TP50
TPAD32-GP
1
PR49
39KR2F-GP
PR49
39KR2F-GP
1 2
C301 
ST15U25VDM-1-GP 
C301 
ST15U25VDM-1-GP 
1 2
H2
HOLE
H2
HOLE
1
PC36 
SC47U6D3V5MX-1-GP 
PC36 
SC47U6D3V5MX-1-GP 
1 2
C254 
SCD1U25V2KX-GP 
C254 
SCD1U25V2KX-GP 
1 2
PR35
30K9R2F-GP
PR35
30K9R2F-GP
1 2
PR42
100R2F-L1-GP-U
PR42
100R2F-L1-GP-U
1 2
H4
HOLE
H4
HOLE
1
PC31 
SC12P50V3JN-GP 
DY PC31 
SC12P50V3JN-GP 
DY 
1 2
PC44
SC220P50V2KX-3GP
PC44
SC220P50V2KX-3GP
1 2
PC41
SC220P50V2KX-3GP
PC41
SC220P50V2KX-3GP
1 2
PQ4
PMBS3904-1-GP
PQ4
PMBS3904-1-GP
3
1
2
PR66
1KR2F-3-GP
PR66
1KR2F-3-GP
1 2
PR44
10R2F-L-GP
PR44
10R2F-L-GP
1 2
PR47
10KR2F-2-GP
PR47
10KR2F-2-GP
1 2
PR530R1206-PAD-1-GP PR530R1206-PAD-1-GP 1 2
PC34 
SC47U6D3V5MX-1-GP 
DY
PC34 
SC47U6D3V5MX-1-GP 
DY1 2
PR46
3K9R2F-GP
PR46
3K9R2F-GP
1 2
PC32
SCD1U25V2KX-GP
PC32
SCD1U25V2KX-GP
1 2
PU4
TPS54320-GP
PU4
TPS54320-GP
RT/CLK1 GND 2GND 3
PVIN4
PVIN5
VIN6 VSENSE 7
COMP 8
SS/TR9
EN 10PH#1111
PH#1212
BOOT13
PWRGD 14
THERMAL_PAD 15
PR32
10KR2F-2-GP
PR32
10KR2F-2-GP
1 2
PR39
D025R3264F-GP
PR39
D025R3264F-GP
1 2
TP48 TPAD32-GPTP48 TPAD32-GP1
H1
HOLE
H1
HOLE
1
PU5
TPS2490DGSR-GP
PU5
TPS2490DGSR-GP
EN1
VREF2
PROG 3
TIMER 4
GND 5
PG 6
OUT 7
GATE 8
SENSE 9
VCC 10 
PR43
1MR3J-L-GP
DY
PR43
1MR3J-L-GP
DY
1 2
C302 
ST15U25VDM-1-GP 
C302 
ST15U25VDM-1-GP 
1 2PR40
4D99R3F-1-GP
PR40
4D99R3F-1-GP
1 2
PC43
SCD068U25V3KX-GP
PC43
SCD068U25V3KX-GP
1 2
PR48
20KR2J-L2-GP
PR48
20KR2J-L2-GP
1 2
PC30 
SC4D7U25V5KX-GP 
PC30 
SC4D7U25V5KX-GP 
1 2
PR55
1KR2F-3-GP
DYPR55
1KR2F-3-GP
DY
1 2
PC29 
SC22U25V5MX-GP 
PC29 
SC22U25V5MX-GP 
1 2
PR38
10KR2F-2-GP
PR38
10KR2F-2-GP
1 2
PR37
3KR2F-GP
PR37
3KR2F-GP
1 2
PR520R1206-PAD-1-GP PR520R1206-PAD-1-GP 1 2
PR41
4D99R3F-1-GP
PR41
4D99R3F-1-GP
1 2
PC38
SC100P50V3JN-2GP
PC38
SC100P50V3JN-2GP
1 2
PR31
10KR2F-2-GP
PR31
10KR2F-2-GP
1 2
PC28 
SC22U25V5MX-GP 
PC28 
SC22U25V5MX-GP 
1 2
PQ3
PMBS3904-2-GP
DY
PQ3
PMBS3904-2-GP
DY
3
1
2
PC40 
SCD01U50V2KX-1GP 
PC40 
SCD01U50V2KX-1GP 
1 2
PC35 
SC47U6D3V5MX-1-GP 
PC35 
SC47U6D3V5MX-1-GP 
1 2
PR36
59KR2F-GP
PR36
59KR2F-GP
1 2
PR45
10KR2F-2-GP
PR45
10KR2F-2-GP
1 2
PC33 
SC3900P50V3KX-GP 
PC33 
SC3900P50V3KX-GP 
1 2
PC42
SCD01U50V2KX-1GP
PC42
SCD01U50V2KX-1GP
1 2
H3
HOLE
H3
HOLE
1
FET
S
S
S
G
D
D
D
D
P-MOS
PU7
SI4435DY DY
FET
S
S
S
G
D
D
D
D
P-MOS
PU7
SI4435DY DY
1
2
3
4
8
7
6
5
PR34
15KR2F-GP
PR34
15KR2F-GP
1 2
G1
COPPER-CLOSE-GP-U
G1
COPPER-CLOSE-GP-U
1 2
PR33
0R3J-0-U-GP
PR33
0R3J-0-U-GP
1 2
PR54
10KR2F-2-GP
DYPR54
10KR2F-2-GP
DY
1 2
TP51 TPAD32-GPTP51 TPAD32-GP1
PQ2
IRLR7843TRPBF-1-GP
PQ2
IRLR7843TRPBF-1-GP
G
D S
PC37 
SC47U6D3V5MX-1-GP 
PC37 
SC47U6D3V5MX-1-GP 
1 2
PR50
6K81R2F-1-GP
PR50
6K81R2F-1-GP
1 2
PC39 
SCD01U50V2KX-1GP 
PC39 
SCD01U50V2KX-1GP 
1 2
C303 
ST15U25VDM-1-GP 
C303 
ST15U25VDM-1-GP 
1 2
PL3
BLM41PG600-GP
PL3
BLM41PG600-GP
1 2



5
5
4
4
3
3
2
2
1
1
D D
C C
B B
A A
BLANK
Title
Size Document Number Rev
Date: Sheet
of
Honey_Badger_SEB 1
BLANK
C
20 22Tuesday, April 07, 2015
Wiwynn
H/W R&D Dept. II
8F,90,Sec. 1,Hsin Tai Wu Rd,
Hsichih, Taipei Hsien 221, Taiwan, R.O.C
Title
Size Document Number Rev
Date: Sheet
of
Honey_Badger_SEB 1
BLANK
C
20 22Tuesday, April 07, 2015
Wiwynn
H/W R&D Dept. II
8F,90,Sec. 1,Hsin Tai Wu Rd,
Hsichih, Taipei Hsien 221, Taiwan, R.O.C
Title
Size Document Number Rev
Date: Sheet
of
Honey_Badger_SEB 1
BLANK
C
20 22Tuesday, April 07, 2015
Wiwynn
H/W R&D Dept. II
8F,90,Sec. 1,Hsin Tai Wu Rd,
Hsichih, Taipei Hsien 221, Taiwan, R.O.C



5
5
4
4
3
3
2
2
1
1
D D
C C
B B
A A
BLANK
Title
Size Document Number Rev
Date: Sheet
of
Honey_Badger_SEB 1
BLANK
C
21 22Tuesday, April 07, 2015
Wiwynn
H/W R&D Dept. II
8F,90,Sec. 1,Hsin Tai Wu Rd,
Hsichih, Taipei Hsien 221, Taiwan, R.O.C
Title
Size Document Number Rev
Date: Sheet
of
Honey_Badger_SEB 1
BLANK
C
21 22Tuesday, April 07, 2015
Wiwynn
H/W R&D Dept. II
8F,90,Sec. 1,Hsin Tai Wu Rd,
Hsichih, Taipei Hsien 221, Taiwan, R.O.C
Title
Size Document Number Rev
Date: Sheet
of
Honey_Badger_SEB 1
BLANK
C
21 22Tuesday, April 07, 2015
Wiwynn
H/W R&D Dept. II
8F,90,Sec. 1,Hsin Tai Wu Rd,
Hsichih, Taipei Hsien 221, Taiwan, R.O.C



5
5
4
4
3
3
2
2
1
1
D D
C C
B B
A A
BLANK
Title
Size Document Number Rev
Date: Sheet
of
Honey_Badger_SEB 1
BLANK
C
22 22Tuesday, April 07, 2015
Wiwynn
H/W R&D Dept. II
8F,90,Sec. 1,Hsin Tai Wu Rd,
Hsichih, Taipei Hsien 221, Taiwan, R.O.C
Title
Size Document Number Rev
Date: Sheet
of
Honey_Badger_SEB 1
BLANK
C
22 22Tuesday, April 07, 2015
Wiwynn
H/W R&D Dept. II
8F,90,Sec. 1,Hsin Tai Wu Rd,
Hsichih, Taipei Hsien 221, Taiwan, R.O.C
Title
Size Document Number Rev
Date: Sheet
of
Honey_Badger_SEB 1
BLANK
C
22 22Tuesday, April 07, 2015
Wiwynn
H/W R&D Dept. II
8F,90,Sec. 1,Hsin Tai Wu Rd,
Hsichih, Taipei Hsien 221, Taiwan, R.O.C